FILE_TYPE = MACRO_DRAWING;
SET COLOR_WIRE YELLOW;
SET COLOR_PROP MONO;
SET COLOR_DOT WHITE;
SET COLOR_ARC YELLOW;
SET COLOR_BODY GREEN;
SET COLOR_NOTE MONO;
SET PROP_DISPLAY VALUE;
SET PAGE_NUMBER P87;
FORCEADD OFFPAGE..3
(1600 5200);
FORCEPROP 2 LAST $XR1 88 
J 0
(1904 5200);
DISPLAY 0.638298 (1904 5200);
PAINT MONO (1904 5200);
FORCEPROP 2 LAST $XR0 62 
J 0
(1814 5200);
DISPLAY 0.638298 (1814 5200);
PAINT MONO (1814 5200);
FORCEPROP 2 LAST CDS_LIB mstr_standard
J 0
(1600 5200);
DISPLAY 0.787234 (1600 5200);
PAINT MONO (1600 5200);
DISPLAY INVISIBLE (1600 5200);
FORCEPROP 1 LAST OFFPAGE TRUE
J 0
(1925 5075);
DISPLAY 0.936170 (1925 5075);
PAINT GREEN (1925 5075);
DISPLAY INVISIBLE (1925 5075);
FORCEPROP 1 LAST COMMENT_BODY TRUE
J 0
(1550 5100);
DISPLAY 0.936170 (1550 5100);
PAINT GREEN (1550 5100);
DISPLAY INVISIBLE (1550 5100);
FORCEPROP 2 LAST PATH I1
J 0
(1800 5275);
DISPLAY 0.787234 (1800 5275);
PAINT MONO (1800 5275);
DISPLAY INVISIBLE (1800 5275);
FORCEADD TAP..6
R 2
(-1750 2200);
FORCEPROP 3 LASTPIN (-1800 2200) SIG_NAME M_M_DQ<8>
J 0
(-1790 2210);
DISPLAY 0.659574 (-1790 2210);
PAINT MONO (-1790 2210);
DISPLAY INVISIBLE (-1790 2210);
FORCEPROP 1 LASTPIN (-1800 2200) BN 8
J 2
(-1750 2210);
DISPLAY 0.617021 (-1750 2210);
PAINT PINK (-1750 2210);
FORCEPROP 2 LAST CDS_LIB mstr_standard
J 2
(-1750 2200);
DISPLAY 0.787234 (-1750 2200);
PAINT MONO (-1750 2200);
DISPLAY INVISIBLE (-1750 2200);
FORCEPROP 1 LAST BODY_TYPE PLUMBING
J 2
(-1750 2150);
DISPLAY 1.234043 (-1750 2150);
PAINT GREEN (-1750 2150);
DISPLAY INVISIBLE (-1750 2150);
FORCEPROP 1 LAST HDL_TAP TRUE
J 2
(-2075 2075);
DISPLAY 1.234043 (-2075 2075);
PAINT GREEN (-2075 2075);
DISPLAY INVISIBLE (-2075 2075);
FORCEPROP 1 LAST PATH I100
J 2
(-1750 2200);
DISPLAY 0.936170 (-1750 2200);
PAINT GREEN (-1750 2200);
DISPLAY INVISIBLE (-1750 2200);
FORCEADD TAP..6
R 2
(-1750 2300);
FORCEPROP 3 LASTPIN (-1800 2300) SIG_NAME M_M_DQ<10>
J 0
(-1790 2310);
DISPLAY 0.659574 (-1790 2310);
PAINT MONO (-1790 2310);
DISPLAY INVISIBLE (-1790 2310);
FORCEPROP 1 LASTPIN (-1800 2300) BN 10
J 2
(-1750 2310);
DISPLAY 0.617021 (-1750 2310);
PAINT PINK (-1750 2310);
FORCEPROP 2 LAST CDS_LIB mstr_standard
J 2
(-1750 2300);
DISPLAY 0.787234 (-1750 2300);
PAINT MONO (-1750 2300);
DISPLAY INVISIBLE (-1750 2300);
FORCEPROP 1 LAST BODY_TYPE PLUMBING
J 2
(-1750 2250);
DISPLAY 1.234043 (-1750 2250);
PAINT GREEN (-1750 2250);
DISPLAY INVISIBLE (-1750 2250);
FORCEPROP 1 LAST HDL_TAP TRUE
J 2
(-2075 2175);
DISPLAY 1.234043 (-2075 2175);
PAINT GREEN (-2075 2175);
DISPLAY INVISIBLE (-2075 2175);
FORCEPROP 1 LAST PATH I101
J 2
(-1750 2300);
DISPLAY 0.936170 (-1750 2300);
PAINT GREEN (-1750 2300);
DISPLAY INVISIBLE (-1750 2300);
FORCEADD TAP..6
R 2
(-1750 2350);
FORCEPROP 3 LASTPIN (-1800 2350) SIG_NAME M_M_DQ<13>
J 0
(-1790 2360);
DISPLAY 0.659574 (-1790 2360);
PAINT MONO (-1790 2360);
DISPLAY INVISIBLE (-1790 2360);
FORCEPROP 1 LASTPIN (-1800 2350) BN 13
J 2
(-1750 2360);
DISPLAY 0.617021 (-1750 2360);
PAINT PINK (-1750 2360);
FORCEPROP 2 LAST CDS_LIB mstr_standard
J 2
(-1750 2350);
DISPLAY 0.787234 (-1750 2350);
PAINT MONO (-1750 2350);
DISPLAY INVISIBLE (-1750 2350);
FORCEPROP 1 LAST BODY_TYPE PLUMBING
J 2
(-1750 2300);
DISPLAY 1.234043 (-1750 2300);
PAINT GREEN (-1750 2300);
DISPLAY INVISIBLE (-1750 2300);
FORCEPROP 1 LAST HDL_TAP TRUE
J 2
(-2075 2225);
DISPLAY 1.234043 (-2075 2225);
PAINT GREEN (-2075 2225);
DISPLAY INVISIBLE (-2075 2225);
FORCEPROP 1 LAST PATH I102
J 2
(-1750 2350);
DISPLAY 0.936170 (-1750 2350);
PAINT GREEN (-1750 2350);
DISPLAY INVISIBLE (-1750 2350);
FORCEADD TAP..6
R 2
(-1750 2100);
FORCEPROP 3 LASTPIN (-1800 2100) SIG_NAME M_M_DQ<6>
J 0
(-1790 2110);
DISPLAY 0.659574 (-1790 2110);
PAINT MONO (-1790 2110);
DISPLAY INVISIBLE (-1790 2110);
FORCEPROP 1 LASTPIN (-1800 2100) BN 6
J 2
(-1750 2110);
DISPLAY 0.617021 (-1750 2110);
PAINT PINK (-1750 2110);
FORCEPROP 2 LAST CDS_LIB mstr_standard
J 2
(-1750 2100);
DISPLAY 0.787234 (-1750 2100);
PAINT MONO (-1750 2100);
DISPLAY INVISIBLE (-1750 2100);
FORCEPROP 1 LAST BODY_TYPE PLUMBING
J 2
(-1750 2050);
DISPLAY 1.234043 (-1750 2050);
PAINT GREEN (-1750 2050);
DISPLAY INVISIBLE (-1750 2050);
FORCEPROP 1 LAST HDL_TAP TRUE
J 2
(-2075 1975);
DISPLAY 1.234043 (-2075 1975);
PAINT GREEN (-2075 1975);
DISPLAY INVISIBLE (-2075 1975);
FORCEPROP 1 LAST PATH I103
J 2
(-1750 2100);
DISPLAY 0.936170 (-1750 2100);
PAINT GREEN (-1750 2100);
DISPLAY INVISIBLE (-1750 2100);
FORCEADD TAP..6
R 2
(-1750 2050);
FORCEPROP 3 LASTPIN (-1800 2050) SIG_NAME M_M_DQ<7>
J 0
(-1790 2060);
DISPLAY 0.659574 (-1790 2060);
PAINT MONO (-1790 2060);
DISPLAY INVISIBLE (-1790 2060);
FORCEPROP 1 LASTPIN (-1800 2050) BN 7
J 2
(-1750 2060);
DISPLAY 0.617021 (-1750 2060);
PAINT PINK (-1750 2060);
FORCEPROP 2 LAST CDS_LIB mstr_standard
J 2
(-1750 2050);
DISPLAY 0.787234 (-1750 2050);
PAINT MONO (-1750 2050);
DISPLAY INVISIBLE (-1750 2050);
FORCEPROP 1 LAST BODY_TYPE PLUMBING
J 2
(-1750 2000);
DISPLAY 1.234043 (-1750 2000);
PAINT GREEN (-1750 2000);
DISPLAY INVISIBLE (-1750 2000);
FORCEPROP 1 LAST HDL_TAP TRUE
J 2
(-2075 1925);
DISPLAY 1.234043 (-2075 1925);
PAINT GREEN (-2075 1925);
DISPLAY INVISIBLE (-2075 1925);
FORCEPROP 1 LAST PATH I104
J 2
(-1750 2050);
DISPLAY 0.936170 (-1750 2050);
PAINT GREEN (-1750 2050);
DISPLAY INVISIBLE (-1750 2050);
FORCEADD TAP..6
R 2
(-1750 2000);
FORCEPROP 3 LASTPIN (-1800 2000) SIG_NAME M_M_DQ<4>
J 0
(-1790 2010);
DISPLAY 0.659574 (-1790 2010);
PAINT MONO (-1790 2010);
DISPLAY INVISIBLE (-1790 2010);
FORCEPROP 1 LASTPIN (-1800 2000) BN 4
J 2
(-1750 2010);
DISPLAY 0.617021 (-1750 2010);
PAINT PINK (-1750 2010);
FORCEPROP 2 LAST CDS_LIB mstr_standard
J 2
(-1750 2000);
DISPLAY 0.787234 (-1750 2000);
PAINT MONO (-1750 2000);
DISPLAY INVISIBLE (-1750 2000);
FORCEPROP 1 LAST BODY_TYPE PLUMBING
J 2
(-1750 1950);
DISPLAY 1.234043 (-1750 1950);
PAINT GREEN (-1750 1950);
DISPLAY INVISIBLE (-1750 1950);
FORCEPROP 1 LAST HDL_TAP TRUE
J 2
(-2075 1875);
DISPLAY 1.234043 (-2075 1875);
PAINT GREEN (-2075 1875);
DISPLAY INVISIBLE (-2075 1875);
FORCEPROP 1 LAST PATH I105
J 2
(-1750 2000);
DISPLAY 0.936170 (-1750 2000);
PAINT GREEN (-1750 2000);
DISPLAY INVISIBLE (-1750 2000);
FORCEADD TAP..6
R 2
(-1750 1950);
FORCEPROP 3 LASTPIN (-1800 1950) SIG_NAME M_M_DQ<5>
J 0
(-1790 1960);
DISPLAY 0.659574 (-1790 1960);
PAINT MONO (-1790 1960);
DISPLAY INVISIBLE (-1790 1960);
FORCEPROP 1 LASTPIN (-1800 1950) BN 5
J 2
(-1750 1960);
DISPLAY 0.617021 (-1750 1960);
PAINT PINK (-1750 1960);
FORCEPROP 2 LAST CDS_LIB mstr_standard
J 2
(-1750 1950);
DISPLAY 0.787234 (-1750 1950);
PAINT MONO (-1750 1950);
DISPLAY INVISIBLE (-1750 1950);
FORCEPROP 1 LAST BODY_TYPE PLUMBING
J 2
(-1750 1900);
DISPLAY 1.234043 (-1750 1900);
PAINT GREEN (-1750 1900);
DISPLAY INVISIBLE (-1750 1900);
FORCEPROP 1 LAST HDL_TAP TRUE
J 2
(-2075 1825);
DISPLAY 1.234043 (-2075 1825);
PAINT GREEN (-2075 1825);
DISPLAY INVISIBLE (-2075 1825);
FORCEPROP 1 LAST PATH I106
J 2
(-1750 1950);
DISPLAY 0.936170 (-1750 1950);
PAINT GREEN (-1750 1950);
DISPLAY INVISIBLE (-1750 1950);
FORCEADD TAP..6
R 2
(-1750 1900);
FORCEPROP 3 LASTPIN (-1800 1900) SIG_NAME M_M_DQ<2>
J 0
(-1790 1910);
DISPLAY 0.659574 (-1790 1910);
PAINT MONO (-1790 1910);
DISPLAY INVISIBLE (-1790 1910);
FORCEPROP 1 LASTPIN (-1800 1900) BN 2
J 2
(-1750 1910);
DISPLAY 0.617021 (-1750 1910);
PAINT PINK (-1750 1910);
FORCEPROP 2 LAST CDS_LIB mstr_standard
J 2
(-1750 1900);
DISPLAY 0.787234 (-1750 1900);
PAINT MONO (-1750 1900);
DISPLAY INVISIBLE (-1750 1900);
FORCEPROP 1 LAST BODY_TYPE PLUMBING
J 2
(-1750 1850);
DISPLAY 1.234043 (-1750 1850);
PAINT GREEN (-1750 1850);
DISPLAY INVISIBLE (-1750 1850);
FORCEPROP 1 LAST HDL_TAP TRUE
J 2
(-2075 1775);
DISPLAY 1.234043 (-2075 1775);
PAINT GREEN (-2075 1775);
DISPLAY INVISIBLE (-2075 1775);
FORCEPROP 1 LAST PATH I107
J 2
(-1750 1900);
DISPLAY 0.936170 (-1750 1900);
PAINT GREEN (-1750 1900);
DISPLAY INVISIBLE (-1750 1900);
FORCEADD TAP..6
R 2
(-1750 1750);
FORCEPROP 3 LASTPIN (-1800 1750) SIG_NAME M_M_DQ<1>
J 0
(-1790 1760);
DISPLAY 0.659574 (-1790 1760);
PAINT MONO (-1790 1760);
DISPLAY INVISIBLE (-1790 1760);
FORCEPROP 1 LASTPIN (-1800 1750) BN 1
J 2
(-1750 1760);
DISPLAY 0.617021 (-1750 1760);
PAINT PINK (-1750 1760);
FORCEPROP 2 LAST CDS_LIB mstr_standard
J 2
(-1750 1750);
DISPLAY 0.787234 (-1750 1750);
PAINT MONO (-1750 1750);
DISPLAY INVISIBLE (-1750 1750);
FORCEPROP 1 LAST BODY_TYPE PLUMBING
J 2
(-1750 1700);
DISPLAY 1.234043 (-1750 1700);
PAINT GREEN (-1750 1700);
DISPLAY INVISIBLE (-1750 1700);
FORCEPROP 1 LAST HDL_TAP TRUE
J 2
(-2075 1625);
DISPLAY 1.234043 (-2075 1625);
PAINT GREEN (-2075 1625);
DISPLAY INVISIBLE (-2075 1625);
FORCEPROP 1 LAST PATH I108
J 2
(-1750 1750);
DISPLAY 0.936170 (-1750 1750);
PAINT GREEN (-1750 1750);
DISPLAY INVISIBLE (-1750 1750);
FORCEADD TAP..6
R 2
(-1750 1850);
FORCEPROP 3 LASTPIN (-1800 1850) SIG_NAME M_M_DQ<3>
J 0
(-1790 1860);
DISPLAY 0.659574 (-1790 1860);
PAINT MONO (-1790 1860);
DISPLAY INVISIBLE (-1790 1860);
FORCEPROP 1 LASTPIN (-1800 1850) BN 3
J 2
(-1750 1860);
DISPLAY 0.617021 (-1750 1860);
PAINT PINK (-1750 1860);
FORCEPROP 2 LAST CDS_LIB mstr_standard
J 2
(-1750 1850);
DISPLAY 0.787234 (-1750 1850);
PAINT MONO (-1750 1850);
DISPLAY INVISIBLE (-1750 1850);
FORCEPROP 1 LAST BODY_TYPE PLUMBING
J 2
(-1750 1800);
DISPLAY 1.234043 (-1750 1800);
PAINT GREEN (-1750 1800);
DISPLAY INVISIBLE (-1750 1800);
FORCEPROP 1 LAST HDL_TAP TRUE
J 2
(-2075 1725);
DISPLAY 1.234043 (-2075 1725);
PAINT GREEN (-2075 1725);
DISPLAY INVISIBLE (-2075 1725);
FORCEPROP 1 LAST PATH I109
J 2
(-1750 1850);
DISPLAY 0.936170 (-1750 1850);
PAINT GREEN (-1750 1850);
DISPLAY INVISIBLE (-1750 1850);
FORCEADD PVDDQ_KLM..1
(-1450 2600);
FORCEPROP 3 LASTPIN (-1450 2550) SIG_NAME PVDDQ_KLM\g
J 0
(-1440 2560);
DISPLAY 0.659574 (-1440 2560);
PAINT MONO (-1440 2560);
DISPLAY INVISIBLE (-1440 2560);
FORCEPROP 1 LAST VOLTAGE 1.2V
J 0
(-1495 2557);
DISPLAY 0.340426 (-1495 2557);
PAINT SKYBLUE (-1495 2557);
DISPLAY INVISIBLE (-1495 2557);
FORCEPROP 2 LAST BOM_COST MEM
J 0
(-1450 2605);
PAINT ORANGE (-1450 2605);
DISPLAY INVISIBLE (-1450 2605);
FORCEPROP 2 LAST CDS_LIB mstr_symbols
J 0
(-1450 2600);
PAINT ORANGE (-1450 2600);
DISPLAY INVISIBLE (-1450 2600);
FORCEPROP 1 LAST BODY_TYPE PLUMBING
J 0
(-1495 2557);
DISPLAY 0.340426 (-1495 2557);
PAINT GREEN (-1495 2557);
DISPLAY INVISIBLE (-1495 2557);
FORCEPROP 1 LAST PATH I11
J 0
(-1400 2625);
DISPLAY 0.872340 (-1400 2625);
PAINT AQUA (-1400 2625);
DISPLAY INVISIBLE (-1400 2625);
FORCEPROP 2 LAST ROOM DDR4_CH_D
J 0
(-1450 2700);
DISPLAY 0.787234 (-1450 2700);
PAINT ORANGE (-1450 2700);
DISPLAY INVISIBLE (-1450 2700);
FORCEPROP 1 LAST HDL_POWER PVDDQ_KLM
J 1
(-1450 2650);
DISPLAY 0.872340 (-1450 2650);
PAINT GREEN (-1450 2650);
DISPLAY INVISIBLE (-1450 2650);
FORCEADD TAP..6
R 2
(-1750 1800);
FORCEPROP 3 LASTPIN (-1800 1800) SIG_NAME M_M_DQ<0>
J 0
(-1790 1810);
DISPLAY 0.659574 (-1790 1810);
PAINT MONO (-1790 1810);
DISPLAY INVISIBLE (-1790 1810);
FORCEPROP 1 LASTPIN (-1800 1800) BN 0
J 2
(-1750 1810);
DISPLAY 0.617021 (-1750 1810);
PAINT PINK (-1750 1810);
FORCEPROP 2 LAST CDS_LIB mstr_standard
J 2
(-1750 1800);
DISPLAY 0.787234 (-1750 1800);
PAINT MONO (-1750 1800);
DISPLAY INVISIBLE (-1750 1800);
FORCEPROP 1 LAST BODY_TYPE PLUMBING
J 2
(-1750 1750);
DISPLAY 1.234043 (-1750 1750);
PAINT GREEN (-1750 1750);
DISPLAY INVISIBLE (-1750 1750);
FORCEPROP 1 LAST HDL_TAP TRUE
J 2
(-2075 1675);
DISPLAY 1.234043 (-2075 1675);
PAINT GREEN (-2075 1675);
DISPLAY INVISIBLE (-2075 1675);
FORCEPROP 1 LAST PATH I110
J 2
(-1750 1800);
DISPLAY 0.936170 (-1750 1800);
PAINT GREEN (-1750 1800);
DISPLAY INVISIBLE (-1750 1800);
FORCEADD TAP..6
(-3250 4850);
FORCEPROP 3 LASTPIN (-3200 4850) SIG_NAME M_M_MA<16>
J 0
(-3190 4860);
DISPLAY 0.659574 (-3190 4860);
PAINT MONO (-3190 4860);
DISPLAY INVISIBLE (-3190 4860);
FORCEPROP 1 LASTPIN (-3200 4850) BN 16
J 0
(-3250 4860);
DISPLAY 0.617021 (-3250 4860);
PAINT PINK (-3250 4860);
FORCEPROP 2 LAST CDS_LIB mstr_standard
J 2
(-3250 4850);
DISPLAY 0.787234 (-3250 4850);
PAINT MONO (-3250 4850);
DISPLAY INVISIBLE (-3250 4850);
FORCEPROP 1 LAST BODY_TYPE PLUMBING
J 0
(-3250 4800);
DISPLAY 1.234043 (-3250 4800);
PAINT GREEN (-3250 4800);
DISPLAY INVISIBLE (-3250 4800);
FORCEPROP 1 LAST HDL_TAP TRUE
J 0
(-2925 4725);
DISPLAY 1.234043 (-2925 4725);
PAINT GREEN (-2925 4725);
DISPLAY INVISIBLE (-2925 4725);
FORCEPROP 1 LAST PATH I112
J 0
(-3250 4850);
DISPLAY 0.936170 (-3250 4850);
PAINT GREEN (-3250 4850);
DISPLAY INVISIBLE (-3250 4850);
FORCEADD TAP..6
(-3250 4900);
FORCEPROP 3 LASTPIN (-3200 4900) SIG_NAME M_M_MA<17>
J 0
(-3190 4910);
DISPLAY 0.659574 (-3190 4910);
PAINT MONO (-3190 4910);
DISPLAY INVISIBLE (-3190 4910);
FORCEPROP 1 LASTPIN (-3200 4900) BN 17
J 0
(-3250 4910);
DISPLAY 0.617021 (-3250 4910);
PAINT PINK (-3250 4910);
FORCEPROP 2 LAST CDS_LIB mstr_standard
J 0
(-3250 4900);
DISPLAY 0.787234 (-3250 4900);
PAINT MONO (-3250 4900);
DISPLAY INVISIBLE (-3250 4900);
FORCEPROP 1 LAST BODY_TYPE PLUMBING
J 0
(-3250 4850);
DISPLAY 1.234043 (-3250 4850);
PAINT GREEN (-3250 4850);
DISPLAY INVISIBLE (-3250 4850);
FORCEPROP 1 LAST HDL_TAP TRUE
J 0
(-2925 4775);
DISPLAY 1.234043 (-2925 4775);
PAINT GREEN (-2925 4775);
DISPLAY INVISIBLE (-2925 4775);
FORCEPROP 1 LAST PATH I113
J 0
(-3250 4900);
DISPLAY 0.936170 (-3250 4900);
PAINT GREEN (-3250 4900);
DISPLAY INVISIBLE (-3250 4900);
FORCEADD TAP..6
(-3250 4800);
FORCEPROP 3 LASTPIN (-3200 4800) SIG_NAME M_M_MA<15>
J 0
(-3190 4810);
DISPLAY 0.659574 (-3190 4810);
PAINT MONO (-3190 4810);
DISPLAY INVISIBLE (-3190 4810);
FORCEPROP 1 LASTPIN (-3200 4800) BN 15
J 0
(-3250 4810);
DISPLAY 0.617021 (-3250 4810);
PAINT PINK (-3250 4810);
FORCEPROP 2 LAST CDS_LIB mstr_standard
J 2
(-3250 4800);
DISPLAY 0.787234 (-3250 4800);
PAINT MONO (-3250 4800);
DISPLAY INVISIBLE (-3250 4800);
FORCEPROP 1 LAST BODY_TYPE PLUMBING
J 0
(-3250 4750);
DISPLAY 1.234043 (-3250 4750);
PAINT GREEN (-3250 4750);
DISPLAY INVISIBLE (-3250 4750);
FORCEPROP 1 LAST HDL_TAP TRUE
J 0
(-2925 4675);
DISPLAY 1.234043 (-2925 4675);
PAINT GREEN (-2925 4675);
DISPLAY INVISIBLE (-2925 4675);
FORCEPROP 1 LAST PATH I114
J 0
(-3250 4800);
DISPLAY 0.936170 (-3250 4800);
PAINT GREEN (-3250 4800);
DISPLAY INVISIBLE (-3250 4800);
FORCEADD TAP..6
(-3250 4750);
FORCEPROP 3 LASTPIN (-3200 4750) SIG_NAME M_M_MA<14>
J 0
(-3190 4760);
DISPLAY 0.659574 (-3190 4760);
PAINT MONO (-3190 4760);
DISPLAY INVISIBLE (-3190 4760);
FORCEPROP 1 LASTPIN (-3200 4750) BN 14
J 0
(-3250 4760);
DISPLAY 0.617021 (-3250 4760);
PAINT PINK (-3250 4760);
FORCEPROP 2 LAST CDS_LIB mstr_standard
J 2
(-3250 4750);
DISPLAY 0.787234 (-3250 4750);
PAINT MONO (-3250 4750);
DISPLAY INVISIBLE (-3250 4750);
FORCEPROP 1 LAST BODY_TYPE PLUMBING
J 0
(-3250 4700);
DISPLAY 1.234043 (-3250 4700);
PAINT GREEN (-3250 4700);
DISPLAY INVISIBLE (-3250 4700);
FORCEPROP 1 LAST HDL_TAP TRUE
J 0
(-2925 4625);
DISPLAY 1.234043 (-2925 4625);
PAINT GREEN (-2925 4625);
DISPLAY INVISIBLE (-2925 4625);
FORCEPROP 1 LAST PATH I115
J 0
(-3250 4750);
DISPLAY 0.936170 (-3250 4750);
PAINT GREEN (-3250 4750);
DISPLAY INVISIBLE (-3250 4750);
FORCEADD TAP..6
(-3250 4700);
FORCEPROP 3 LASTPIN (-3200 4700) SIG_NAME M_M_MA<13>
J 0
(-3190 4710);
DISPLAY 0.659574 (-3190 4710);
PAINT MONO (-3190 4710);
DISPLAY INVISIBLE (-3190 4710);
FORCEPROP 1 LASTPIN (-3200 4700) BN 13
J 0
(-3250 4710);
DISPLAY 0.617021 (-3250 4710);
PAINT PINK (-3250 4710);
FORCEPROP 2 LAST CDS_LIB mstr_standard
J 2
(-3250 4700);
DISPLAY 0.787234 (-3250 4700);
PAINT MONO (-3250 4700);
DISPLAY INVISIBLE (-3250 4700);
FORCEPROP 1 LAST BODY_TYPE PLUMBING
J 0
(-3250 4650);
DISPLAY 1.234043 (-3250 4650);
PAINT GREEN (-3250 4650);
DISPLAY INVISIBLE (-3250 4650);
FORCEPROP 1 LAST HDL_TAP TRUE
J 0
(-2925 4575);
DISPLAY 1.234043 (-2925 4575);
PAINT GREEN (-2925 4575);
DISPLAY INVISIBLE (-2925 4575);
FORCEPROP 1 LAST PATH I116
J 0
(-3250 4700);
DISPLAY 0.936170 (-3250 4700);
PAINT GREEN (-3250 4700);
DISPLAY INVISIBLE (-3250 4700);
FORCEADD TAP..6
(-3250 4650);
FORCEPROP 3 LASTPIN (-3200 4650) SIG_NAME M_M_MA<12>
J 0
(-3190 4660);
DISPLAY 0.659574 (-3190 4660);
PAINT MONO (-3190 4660);
DISPLAY INVISIBLE (-3190 4660);
FORCEPROP 1 LASTPIN (-3200 4650) BN 12
J 0
(-3250 4660);
DISPLAY 0.617021 (-3250 4660);
PAINT PINK (-3250 4660);
FORCEPROP 2 LAST CDS_LIB mstr_standard
J 2
(-3250 4650);
DISPLAY 0.787234 (-3250 4650);
PAINT MONO (-3250 4650);
DISPLAY INVISIBLE (-3250 4650);
FORCEPROP 1 LAST BODY_TYPE PLUMBING
J 0
(-3250 4600);
DISPLAY 1.234043 (-3250 4600);
PAINT GREEN (-3250 4600);
DISPLAY INVISIBLE (-3250 4600);
FORCEPROP 1 LAST HDL_TAP TRUE
J 0
(-2925 4525);
DISPLAY 1.234043 (-2925 4525);
PAINT GREEN (-2925 4525);
DISPLAY INVISIBLE (-2925 4525);
FORCEPROP 1 LAST PATH I117
J 0
(-3250 4650);
DISPLAY 0.936170 (-3250 4650);
PAINT GREEN (-3250 4650);
DISPLAY INVISIBLE (-3250 4650);
FORCEADD TAP..6
(-3250 4600);
FORCEPROP 3 LASTPIN (-3200 4600) SIG_NAME M_M_MA<11>
J 0
(-3190 4610);
DISPLAY 0.659574 (-3190 4610);
PAINT MONO (-3190 4610);
DISPLAY INVISIBLE (-3190 4610);
FORCEPROP 1 LASTPIN (-3200 4600) BN 11
J 0
(-3250 4610);
DISPLAY 0.617021 (-3250 4610);
PAINT PINK (-3250 4610);
FORCEPROP 2 LAST CDS_LIB mstr_standard
J 2
(-3250 4600);
DISPLAY 0.787234 (-3250 4600);
PAINT MONO (-3250 4600);
DISPLAY INVISIBLE (-3250 4600);
FORCEPROP 1 LAST BODY_TYPE PLUMBING
J 0
(-3250 4550);
DISPLAY 1.234043 (-3250 4550);
PAINT GREEN (-3250 4550);
DISPLAY INVISIBLE (-3250 4550);
FORCEPROP 1 LAST HDL_TAP TRUE
J 0
(-2925 4475);
DISPLAY 1.234043 (-2925 4475);
PAINT GREEN (-2925 4475);
DISPLAY INVISIBLE (-2925 4475);
FORCEPROP 1 LAST PATH I118
J 0
(-3250 4600);
DISPLAY 0.936170 (-3250 4600);
PAINT GREEN (-3250 4600);
DISPLAY INVISIBLE (-3250 4600);
FORCEADD TAP..6
(-3250 4550);
FORCEPROP 3 LASTPIN (-3200 4550) SIG_NAME M_M_MA<10>
J 0
(-3190 4560);
DISPLAY 0.659574 (-3190 4560);
PAINT MONO (-3190 4560);
DISPLAY INVISIBLE (-3190 4560);
FORCEPROP 1 LASTPIN (-3200 4550) BN 10
J 0
(-3250 4560);
DISPLAY 0.617021 (-3250 4560);
PAINT PINK (-3250 4560);
FORCEPROP 2 LAST CDS_LIB mstr_standard
J 2
(-3250 4550);
DISPLAY 0.787234 (-3250 4550);
PAINT MONO (-3250 4550);
DISPLAY INVISIBLE (-3250 4550);
FORCEPROP 1 LAST BODY_TYPE PLUMBING
J 0
(-3250 4500);
DISPLAY 1.234043 (-3250 4500);
PAINT GREEN (-3250 4500);
DISPLAY INVISIBLE (-3250 4500);
FORCEPROP 1 LAST HDL_TAP TRUE
J 0
(-2925 4425);
DISPLAY 1.234043 (-2925 4425);
PAINT GREEN (-2925 4425);
DISPLAY INVISIBLE (-2925 4425);
FORCEPROP 1 LAST PATH I119
J 0
(-3250 4550);
DISPLAY 0.936170 (-3250 4550);
PAINT GREEN (-3250 4550);
DISPLAY INVISIBLE (-3250 4550);
FORCEADD TAP..6
R 2
(900 4500);
FORCEPROP 3 LASTPIN (850 4500) SIG_NAME M_M_DQS_DN<11>
J 0
(860 4510);
DISPLAY 0.659574 (860 4510);
PAINT MONO (860 4510);
DISPLAY INVISIBLE (860 4510);
FORCEPROP 1 LASTPIN (850 4500) BN 11
J 2
(900 4510);
DISPLAY 0.617021 (900 4510);
PAINT PINK (900 4510);
FORCEPROP 2 LAST CDS_LIB mstr_standard
J 0
(900 4500);
DISPLAY 0.787234 (900 4500);
PAINT MONO (900 4500);
DISPLAY INVISIBLE (900 4500);
FORCEPROP 1 LAST BODY_TYPE PLUMBING
J 2
(900 4450);
DISPLAY 1.234043 (900 4450);
PAINT GREEN (900 4450);
DISPLAY INVISIBLE (900 4450);
FORCEPROP 1 LAST HDL_TAP TRUE
J 2
(575 4375);
DISPLAY 1.234043 (575 4375);
PAINT GREEN (575 4375);
DISPLAY INVISIBLE (575 4375);
FORCEPROP 1 LAST PATH I12
J 2
(900 4500);
DISPLAY 0.936170 (900 4500);
PAINT GREEN (900 4500);
DISPLAY INVISIBLE (900 4500);
FORCEADD TAP..6
(-3250 4450);
FORCEPROP 3 LASTPIN (-3200 4450) SIG_NAME M_M_MA<8>
J 0
(-3190 4460);
DISPLAY 0.659574 (-3190 4460);
PAINT MONO (-3190 4460);
DISPLAY INVISIBLE (-3190 4460);
FORCEPROP 1 LASTPIN (-3200 4450) BN 8
J 0
(-3250 4460);
DISPLAY 0.617021 (-3250 4460);
PAINT PINK (-3250 4460);
FORCEPROP 2 LAST CDS_LIB mstr_standard
J 2
(-3250 4450);
DISPLAY 0.787234 (-3250 4450);
PAINT MONO (-3250 4450);
DISPLAY INVISIBLE (-3250 4450);
FORCEPROP 1 LAST BODY_TYPE PLUMBING
J 0
(-3250 4400);
DISPLAY 1.234043 (-3250 4400);
PAINT GREEN (-3250 4400);
DISPLAY INVISIBLE (-3250 4400);
FORCEPROP 1 LAST HDL_TAP TRUE
J 0
(-2925 4325);
DISPLAY 1.234043 (-2925 4325);
PAINT GREEN (-2925 4325);
DISPLAY INVISIBLE (-2925 4325);
FORCEPROP 1 LAST PATH I120
J 0
(-3250 4450);
DISPLAY 0.936170 (-3250 4450);
PAINT GREEN (-3250 4450);
DISPLAY INVISIBLE (-3250 4450);
FORCEADD TAP..6
(-3250 4500);
FORCEPROP 3 LASTPIN (-3200 4500) SIG_NAME M_M_MA<9>
J 0
(-3190 4510);
DISPLAY 0.659574 (-3190 4510);
PAINT MONO (-3190 4510);
DISPLAY INVISIBLE (-3190 4510);
FORCEPROP 1 LASTPIN (-3200 4500) BN 9
J 0
(-3250 4510);
DISPLAY 0.617021 (-3250 4510);
PAINT PINK (-3250 4510);
FORCEPROP 2 LAST CDS_LIB mstr_standard
J 2
(-3250 4500);
DISPLAY 0.787234 (-3250 4500);
PAINT MONO (-3250 4500);
DISPLAY INVISIBLE (-3250 4500);
FORCEPROP 1 LAST BODY_TYPE PLUMBING
J 0
(-3250 4450);
DISPLAY 1.234043 (-3250 4450);
PAINT GREEN (-3250 4450);
DISPLAY INVISIBLE (-3250 4450);
FORCEPROP 1 LAST HDL_TAP TRUE
J 0
(-2925 4375);
DISPLAY 1.234043 (-2925 4375);
PAINT GREEN (-2925 4375);
DISPLAY INVISIBLE (-2925 4375);
FORCEPROP 1 LAST PATH I121
J 0
(-3250 4500);
DISPLAY 0.936170 (-3250 4500);
PAINT GREEN (-3250 4500);
DISPLAY INVISIBLE (-3250 4500);
FORCEADD TAP..6
(-3250 4400);
FORCEPROP 3 LASTPIN (-3200 4400) SIG_NAME M_M_MA<7>
J 0
(-3190 4410);
DISPLAY 0.659574 (-3190 4410);
PAINT MONO (-3190 4410);
DISPLAY INVISIBLE (-3190 4410);
FORCEPROP 1 LASTPIN (-3200 4400) BN 7
J 0
(-3250 4410);
DISPLAY 0.617021 (-3250 4410);
PAINT PINK (-3250 4410);
FORCEPROP 2 LAST CDS_LIB mstr_standard
J 2
(-3250 4400);
DISPLAY 0.787234 (-3250 4400);
PAINT MONO (-3250 4400);
DISPLAY INVISIBLE (-3250 4400);
FORCEPROP 1 LAST BODY_TYPE PLUMBING
J 0
(-3250 4350);
DISPLAY 1.234043 (-3250 4350);
PAINT GREEN (-3250 4350);
DISPLAY INVISIBLE (-3250 4350);
FORCEPROP 1 LAST HDL_TAP TRUE
J 0
(-2925 4275);
DISPLAY 1.234043 (-2925 4275);
PAINT GREEN (-2925 4275);
DISPLAY INVISIBLE (-2925 4275);
FORCEPROP 1 LAST PATH I122
J 0
(-3250 4400);
DISPLAY 0.936170 (-3250 4400);
PAINT GREEN (-3250 4400);
DISPLAY INVISIBLE (-3250 4400);
FORCEADD TAP..6
(-3250 4350);
FORCEPROP 3 LASTPIN (-3200 4350) SIG_NAME M_M_MA<6>
J 0
(-3190 4360);
DISPLAY 0.659574 (-3190 4360);
PAINT MONO (-3190 4360);
DISPLAY INVISIBLE (-3190 4360);
FORCEPROP 1 LASTPIN (-3200 4350) BN 6
J 0
(-3250 4360);
DISPLAY 0.617021 (-3250 4360);
PAINT PINK (-3250 4360);
FORCEPROP 2 LAST CDS_LIB mstr_standard
J 2
(-3250 4350);
DISPLAY 0.787234 (-3250 4350);
PAINT MONO (-3250 4350);
DISPLAY INVISIBLE (-3250 4350);
FORCEPROP 1 LAST BODY_TYPE PLUMBING
J 0
(-3250 4300);
DISPLAY 1.234043 (-3250 4300);
PAINT GREEN (-3250 4300);
DISPLAY INVISIBLE (-3250 4300);
FORCEPROP 1 LAST HDL_TAP TRUE
J 0
(-2925 4225);
DISPLAY 1.234043 (-2925 4225);
PAINT GREEN (-2925 4225);
DISPLAY INVISIBLE (-2925 4225);
FORCEPROP 1 LAST PATH I123
J 0
(-3250 4350);
DISPLAY 0.936170 (-3250 4350);
PAINT GREEN (-3250 4350);
DISPLAY INVISIBLE (-3250 4350);
FORCEADD TAP..6
(-3250 4300);
FORCEPROP 3 LASTPIN (-3200 4300) SIG_NAME M_M_MA<5>
J 0
(-3190 4310);
DISPLAY 0.659574 (-3190 4310);
PAINT MONO (-3190 4310);
DISPLAY INVISIBLE (-3190 4310);
FORCEPROP 1 LASTPIN (-3200 4300) BN 5
J 0
(-3250 4310);
DISPLAY 0.617021 (-3250 4310);
PAINT PINK (-3250 4310);
FORCEPROP 2 LAST CDS_LIB mstr_standard
J 2
(-3250 4300);
DISPLAY 0.787234 (-3250 4300);
PAINT MONO (-3250 4300);
DISPLAY INVISIBLE (-3250 4300);
FORCEPROP 1 LAST BODY_TYPE PLUMBING
J 0
(-3250 4250);
DISPLAY 1.234043 (-3250 4250);
PAINT GREEN (-3250 4250);
DISPLAY INVISIBLE (-3250 4250);
FORCEPROP 1 LAST HDL_TAP TRUE
J 0
(-2925 4175);
DISPLAY 1.234043 (-2925 4175);
PAINT GREEN (-2925 4175);
DISPLAY INVISIBLE (-2925 4175);
FORCEPROP 1 LAST PATH I124
J 0
(-3250 4300);
DISPLAY 0.936170 (-3250 4300);
PAINT GREEN (-3250 4300);
DISPLAY INVISIBLE (-3250 4300);
FORCEADD TAP..6
(-3250 4250);
FORCEPROP 3 LASTPIN (-3200 4250) SIG_NAME M_M_MA<4>
J 0
(-3190 4260);
DISPLAY 0.659574 (-3190 4260);
PAINT MONO (-3190 4260);
DISPLAY INVISIBLE (-3190 4260);
FORCEPROP 1 LASTPIN (-3200 4250) BN 4
J 0
(-3250 4260);
DISPLAY 0.617021 (-3250 4260);
PAINT PINK (-3250 4260);
FORCEPROP 2 LAST CDS_LIB mstr_standard
J 2
(-3250 4250);
DISPLAY 0.787234 (-3250 4250);
PAINT MONO (-3250 4250);
DISPLAY INVISIBLE (-3250 4250);
FORCEPROP 1 LAST BODY_TYPE PLUMBING
J 0
(-3250 4200);
DISPLAY 1.234043 (-3250 4200);
PAINT GREEN (-3250 4200);
DISPLAY INVISIBLE (-3250 4200);
FORCEPROP 1 LAST HDL_TAP TRUE
J 0
(-2925 4125);
DISPLAY 1.234043 (-2925 4125);
PAINT GREEN (-2925 4125);
DISPLAY INVISIBLE (-2925 4125);
FORCEPROP 1 LAST PATH I125
J 0
(-3250 4250);
DISPLAY 0.936170 (-3250 4250);
PAINT GREEN (-3250 4250);
DISPLAY INVISIBLE (-3250 4250);
FORCEADD TAP..6
(-3250 4200);
FORCEPROP 3 LASTPIN (-3200 4200) SIG_NAME M_M_MA<3>
J 0
(-3190 4210);
DISPLAY 0.659574 (-3190 4210);
PAINT MONO (-3190 4210);
DISPLAY INVISIBLE (-3190 4210);
FORCEPROP 1 LASTPIN (-3200 4200) BN 3
J 0
(-3250 4210);
DISPLAY 0.617021 (-3250 4210);
PAINT PINK (-3250 4210);
FORCEPROP 2 LAST CDS_LIB mstr_standard
J 2
(-3250 4200);
DISPLAY 0.787234 (-3250 4200);
PAINT MONO (-3250 4200);
DISPLAY INVISIBLE (-3250 4200);
FORCEPROP 1 LAST BODY_TYPE PLUMBING
J 0
(-3250 4150);
DISPLAY 1.234043 (-3250 4150);
PAINT GREEN (-3250 4150);
DISPLAY INVISIBLE (-3250 4150);
FORCEPROP 1 LAST HDL_TAP TRUE
J 0
(-2925 4075);
DISPLAY 1.234043 (-2925 4075);
PAINT GREEN (-2925 4075);
DISPLAY INVISIBLE (-2925 4075);
FORCEPROP 1 LAST PATH I126
J 0
(-3250 4200);
DISPLAY 0.936170 (-3250 4200);
PAINT GREEN (-3250 4200);
DISPLAY INVISIBLE (-3250 4200);
FORCEADD TAP..6
(-3250 4150);
FORCEPROP 3 LASTPIN (-3200 4150) SIG_NAME M_M_MA<2>
J 0
(-3190 4160);
DISPLAY 0.659574 (-3190 4160);
PAINT MONO (-3190 4160);
DISPLAY INVISIBLE (-3190 4160);
FORCEPROP 1 LASTPIN (-3200 4150) BN 2
J 0
(-3250 4160);
DISPLAY 0.617021 (-3250 4160);
PAINT PINK (-3250 4160);
FORCEPROP 2 LAST CDS_LIB mstr_standard
J 2
(-3250 4150);
DISPLAY 0.787234 (-3250 4150);
PAINT MONO (-3250 4150);
DISPLAY INVISIBLE (-3250 4150);
FORCEPROP 1 LAST BODY_TYPE PLUMBING
J 0
(-3250 4100);
DISPLAY 1.234043 (-3250 4100);
PAINT GREEN (-3250 4100);
DISPLAY INVISIBLE (-3250 4100);
FORCEPROP 1 LAST HDL_TAP TRUE
J 0
(-2925 4025);
DISPLAY 1.234043 (-2925 4025);
PAINT GREEN (-2925 4025);
DISPLAY INVISIBLE (-2925 4025);
FORCEPROP 1 LAST PATH I127
J 0
(-3250 4150);
DISPLAY 0.936170 (-3250 4150);
PAINT GREEN (-3250 4150);
DISPLAY INVISIBLE (-3250 4150);
FORCEADD TAP..6
(-3250 4100);
FORCEPROP 3 LASTPIN (-3200 4100) SIG_NAME M_M_MA<1>
J 0
(-3190 4110);
DISPLAY 0.659574 (-3190 4110);
PAINT MONO (-3190 4110);
DISPLAY INVISIBLE (-3190 4110);
FORCEPROP 1 LASTPIN (-3200 4100) BN 1
J 0
(-3250 4110);
DISPLAY 0.617021 (-3250 4110);
PAINT PINK (-3250 4110);
FORCEPROP 2 LAST CDS_LIB mstr_standard
J 2
(-3250 4100);
DISPLAY 0.787234 (-3250 4100);
PAINT MONO (-3250 4100);
DISPLAY INVISIBLE (-3250 4100);
FORCEPROP 1 LAST BODY_TYPE PLUMBING
J 0
(-3250 4050);
DISPLAY 1.234043 (-3250 4050);
PAINT GREEN (-3250 4050);
DISPLAY INVISIBLE (-3250 4050);
FORCEPROP 1 LAST HDL_TAP TRUE
J 0
(-2925 3975);
DISPLAY 1.234043 (-2925 3975);
PAINT GREEN (-2925 3975);
DISPLAY INVISIBLE (-2925 3975);
FORCEPROP 1 LAST PATH I128
J 0
(-3250 4100);
DISPLAY 0.936170 (-3250 4100);
PAINT GREEN (-3250 4100);
DISPLAY INVISIBLE (-3250 4100);
FORCEADD TAP..6
(-3250 4050);
FORCEPROP 3 LASTPIN (-3200 4050) SIG_NAME M_M_MA<0>
J 0
(-3190 4060);
DISPLAY 0.659574 (-3190 4060);
PAINT MONO (-3190 4060);
DISPLAY INVISIBLE (-3190 4060);
FORCEPROP 1 LASTPIN (-3200 4050) BN 0
J 0
(-3250 4060);
DISPLAY 0.617021 (-3250 4060);
PAINT PINK (-3250 4060);
FORCEPROP 2 LAST CDS_LIB mstr_standard
J 2
(-3250 4050);
DISPLAY 0.787234 (-3250 4050);
PAINT MONO (-3250 4050);
DISPLAY INVISIBLE (-3250 4050);
FORCEPROP 1 LAST BODY_TYPE PLUMBING
J 0
(-3250 4000);
DISPLAY 1.234043 (-3250 4000);
PAINT GREEN (-3250 4000);
DISPLAY INVISIBLE (-3250 4000);
FORCEPROP 1 LAST HDL_TAP TRUE
J 0
(-2925 3925);
DISPLAY 1.234043 (-2925 3925);
PAINT GREEN (-2925 3925);
DISPLAY INVISIBLE (-2925 3925);
FORCEPROP 1 LAST PATH I129
J 0
(-3250 4050);
DISPLAY 0.936170 (-3250 4050);
PAINT GREEN (-3250 4050);
DISPLAY INVISIBLE (-3250 4050);
FORCEADD TAP..6
R 2
(900 4400);
FORCEPROP 3 LASTPIN (850 4400) SIG_NAME M_M_DQS_DN<10>
J 0
(860 4410);
DISPLAY 0.659574 (860 4410);
PAINT MONO (860 4410);
DISPLAY INVISIBLE (860 4410);
FORCEPROP 1 LASTPIN (850 4400) BN 10
J 2
(900 4410);
DISPLAY 0.617021 (900 4410);
PAINT PINK (900 4410);
FORCEPROP 2 LAST CDS_LIB mstr_standard
J 0
(900 4400);
DISPLAY 0.787234 (900 4400);
PAINT MONO (900 4400);
DISPLAY INVISIBLE (900 4400);
FORCEPROP 1 LAST BODY_TYPE PLUMBING
J 2
(900 4350);
DISPLAY 1.234043 (900 4350);
PAINT GREEN (900 4350);
DISPLAY INVISIBLE (900 4350);
FORCEPROP 1 LAST HDL_TAP TRUE
J 2
(575 4275);
DISPLAY 1.234043 (575 4275);
PAINT GREEN (575 4275);
DISPLAY INVISIBLE (575 4275);
FORCEPROP 1 LAST PATH I13
J 2
(900 4400);
DISPLAY 0.936170 (900 4400);
PAINT GREEN (900 4400);
DISPLAY INVISIBLE (900 4400);
FORCEADD TAP..6
(-3250 3950);
FORCEPROP 3 LASTPIN (-3200 3950) SIG_NAME M_M_BA<1>
J 0
(-3190 3960);
DISPLAY 0.659574 (-3190 3960);
PAINT MONO (-3190 3960);
DISPLAY INVISIBLE (-3190 3960);
FORCEPROP 1 LASTPIN (-3200 3950) BN 1
J 0
(-3250 3960);
DISPLAY 0.617021 (-3250 3960);
PAINT PINK (-3250 3960);
FORCEPROP 2 LAST CDS_LIB mstr_standard
J 0
(-3250 3950);
DISPLAY 0.787234 (-3250 3950);
PAINT MONO (-3250 3950);
DISPLAY INVISIBLE (-3250 3950);
FORCEPROP 1 LAST BODY_TYPE PLUMBING
J 0
(-3250 3900);
DISPLAY 1.234043 (-3250 3900);
PAINT GREEN (-3250 3900);
DISPLAY INVISIBLE (-3250 3900);
FORCEPROP 1 LAST HDL_TAP TRUE
J 0
(-2925 3825);
DISPLAY 1.234043 (-2925 3825);
PAINT GREEN (-2925 3825);
DISPLAY INVISIBLE (-2925 3825);
FORCEPROP 1 LAST PATH I130
J 0
(-3250 3950);
DISPLAY 0.936170 (-3250 3950);
PAINT GREEN (-3250 3950);
DISPLAY INVISIBLE (-3250 3950);
FORCEADD OFFPAGE..1
(-3850 4950);
FORCEPROP 2 LAST $XR1 88 
J 0
(-4191 4950);
DISPLAY 0.638298 (-4191 4950);
PAINT MONO (-4191 4950);
FORCEPROP 2 LAST $XR0 62 
J 0
(-4101 4950);
DISPLAY 0.638298 (-4101 4950);
PAINT MONO (-4101 4950);
FORCEPROP 2 LAST CDS_LIB mstr_standard
J 0
(-3850 4950);
DISPLAY 0.787234 (-3850 4950);
PAINT MONO (-3850 4950);
DISPLAY INVISIBLE (-3850 4950);
FORCEPROP 1 LAST OFFPAGE TRUE
J 0
(-3525 4825);
DISPLAY 0.936170 (-3525 4825);
PAINT GREEN (-3525 4825);
DISPLAY INVISIBLE (-3525 4825);
FORCEPROP 1 LAST COMMENT_BODY TRUE
J 0
(-3725 4850);
DISPLAY 0.936170 (-3725 4850);
PAINT GREEN (-3725 4850);
DISPLAY INVISIBLE (-3725 4850);
FORCEPROP 2 LAST PATH I131
J 0
(-3800 5025);
DISPLAY 0.787234 (-3800 5025);
PAINT MONO (-3800 5025);
DISPLAY INVISIBLE (-3800 5025);
FORCEADD OFFPAGE..1
(-3850 4000);
FORCEPROP 2 LAST $XR0 62 
J 0
(-4101 4000);
DISPLAY 0.638298 (-4101 4000);
PAINT MONO (-4101 4000);
FORCEPROP 2 LAST $XR1 88 
J 0
(-4191 4000);
DISPLAY 0.638298 (-4191 4000);
PAINT MONO (-4191 4000);
FORCEPROP 2 LAST CDS_LIB mstr_standard
J 0
(-3850 4000);
DISPLAY 0.787234 (-3850 4000);
PAINT MONO (-3850 4000);
DISPLAY INVISIBLE (-3850 4000);
FORCEPROP 1 LAST OFFPAGE TRUE
J 0
(-3525 3875);
DISPLAY 0.936170 (-3525 3875);
PAINT GREEN (-3525 3875);
DISPLAY INVISIBLE (-3525 3875);
FORCEPROP 1 LAST COMMENT_BODY TRUE
J 0
(-3725 3900);
DISPLAY 0.936170 (-3725 3900);
PAINT GREEN (-3725 3900);
DISPLAY INVISIBLE (-3725 3900);
FORCEPROP 2 LAST PATH I132
J 0
(-3800 4075);
DISPLAY 0.787234 (-3800 4075);
PAINT MONO (-3800 4075);
DISPLAY INVISIBLE (-3800 4075);
FORCEADD TAP..6
(-3250 3900);
FORCEPROP 3 LASTPIN (-3200 3900) SIG_NAME M_M_BA<0>
J 0
(-3190 3910);
DISPLAY 0.659574 (-3190 3910);
PAINT MONO (-3190 3910);
DISPLAY INVISIBLE (-3190 3910);
FORCEPROP 1 LASTPIN (-3200 3900) BN 0
J 0
(-3250 3910);
DISPLAY 0.617021 (-3250 3910);
PAINT PINK (-3250 3910);
FORCEPROP 2 LAST CDS_LIB mstr_standard
J 0
(-3250 3900);
DISPLAY 0.787234 (-3250 3900);
PAINT MONO (-3250 3900);
DISPLAY INVISIBLE (-3250 3900);
FORCEPROP 1 LAST BODY_TYPE PLUMBING
J 0
(-3250 3850);
DISPLAY 1.234043 (-3250 3850);
PAINT GREEN (-3250 3850);
DISPLAY INVISIBLE (-3250 3850);
FORCEPROP 1 LAST HDL_TAP TRUE
J 0
(-2925 3775);
DISPLAY 1.234043 (-2925 3775);
PAINT GREEN (-2925 3775);
DISPLAY INVISIBLE (-2925 3775);
FORCEPROP 1 LAST PATH I133
J 0
(-3250 3900);
DISPLAY 0.936170 (-3250 3900);
PAINT GREEN (-3250 3900);
DISPLAY INVISIBLE (-3250 3900);
FORCEADD TAP..6
(-3250 3800);
FORCEPROP 3 LASTPIN (-3200 3800) SIG_NAME M_M_BG<0>
J 0
(-3190 3810);
DISPLAY 0.659574 (-3190 3810);
PAINT MONO (-3190 3810);
DISPLAY INVISIBLE (-3190 3810);
FORCEPROP 1 LASTPIN (-3200 3800) BN 0
J 0
(-3250 3810);
DISPLAY 0.617021 (-3250 3810);
PAINT PINK (-3250 3810);
FORCEPROP 2 LAST CDS_LIB mstr_standard
J 0
(-3250 3800);
DISPLAY 0.787234 (-3250 3800);
PAINT MONO (-3250 3800);
DISPLAY INVISIBLE (-3250 3800);
FORCEPROP 1 LAST BODY_TYPE PLUMBING
J 0
(-3250 3750);
DISPLAY 1.234043 (-3250 3750);
PAINT GREEN (-3250 3750);
DISPLAY INVISIBLE (-3250 3750);
FORCEPROP 1 LAST HDL_TAP TRUE
J 0
(-2925 3675);
DISPLAY 1.234043 (-2925 3675);
PAINT GREEN (-2925 3675);
DISPLAY INVISIBLE (-2925 3675);
FORCEPROP 1 LAST PATH I134
J 0
(-3250 3800);
DISPLAY 0.936170 (-3250 3800);
PAINT GREEN (-3250 3800);
DISPLAY INVISIBLE (-3250 3800);
FORCEADD TAP..6
(-3250 3850);
FORCEPROP 3 LASTPIN (-3200 3850) SIG_NAME M_M_BG<1>
J 0
(-3190 3860);
DISPLAY 0.659574 (-3190 3860);
PAINT MONO (-3190 3860);
DISPLAY INVISIBLE (-3190 3860);
FORCEPROP 1 LASTPIN (-3200 3850) BN 1
J 0
(-3250 3860);
DISPLAY 0.617021 (-3250 3860);
PAINT PINK (-3250 3860);
FORCEPROP 2 LAST CDS_LIB mstr_standard
J 0
(-3250 3850);
DISPLAY 0.787234 (-3250 3850);
PAINT MONO (-3250 3850);
DISPLAY INVISIBLE (-3250 3850);
FORCEPROP 1 LAST BODY_TYPE PLUMBING
J 0
(-3250 3800);
DISPLAY 1.234043 (-3250 3800);
PAINT GREEN (-3250 3800);
DISPLAY INVISIBLE (-3250 3800);
FORCEPROP 1 LAST HDL_TAP TRUE
J 0
(-2925 3725);
DISPLAY 1.234043 (-2925 3725);
PAINT GREEN (-2925 3725);
DISPLAY INVISIBLE (-2925 3725);
FORCEPROP 1 LAST PATH I135
J 0
(-3250 3850);
DISPLAY 0.936170 (-3250 3850);
PAINT GREEN (-3250 3850);
DISPLAY INVISIBLE (-3250 3850);
FORCEADD OFFPAGE..1
(-3850 3500);
FORCEPROP 2 LAST $XR1 88 
J 0
(-4191 3500);
DISPLAY 0.638298 (-4191 3500);
PAINT MONO (-4191 3500);
FORCEPROP 2 LAST $XR0 62 
J 0
(-4101 3500);
DISPLAY 0.638298 (-4101 3500);
PAINT MONO (-4101 3500);
FORCEPROP 2 LAST CDS_LIB mstr_standard
J 0
(-3850 3500);
DISPLAY 0.787234 (-3850 3500);
PAINT MONO (-3850 3500);
DISPLAY INVISIBLE (-3850 3500);
FORCEPROP 1 LAST OFFPAGE TRUE
J 0
(-3525 3375);
DISPLAY 0.936170 (-3525 3375);
PAINT GREEN (-3525 3375);
DISPLAY INVISIBLE (-3525 3375);
FORCEPROP 1 LAST COMMENT_BODY TRUE
J 0
(-3725 3400);
DISPLAY 0.936170 (-3725 3400);
PAINT GREEN (-3725 3400);
DISPLAY INVISIBLE (-3725 3400);
FORCEPROP 2 LAST PATH I136
J 0
(-3800 3575);
DISPLAY 0.787234 (-3800 3575);
PAINT MONO (-3800 3575);
DISPLAY INVISIBLE (-3800 3575);
FORCEADD OFFPAGE..1
(-3850 3900);
FORCEPROP 2 LAST $XR1 88 
J 0
(-4191 3900);
DISPLAY 0.638298 (-4191 3900);
PAINT MONO (-4191 3900);
FORCEPROP 2 LAST $XR0 62 
J 0
(-4101 3900);
DISPLAY 0.638298 (-4101 3900);
PAINT MONO (-4101 3900);
FORCEPROP 2 LAST CDS_LIB mstr_standard
J 0
(-3850 3900);
DISPLAY 0.787234 (-3850 3900);
PAINT MONO (-3850 3900);
DISPLAY INVISIBLE (-3850 3900);
FORCEPROP 1 LAST OFFPAGE TRUE
J 0
(-3525 3775);
DISPLAY 0.936170 (-3525 3775);
PAINT GREEN (-3525 3775);
DISPLAY INVISIBLE (-3525 3775);
FORCEPROP 1 LAST COMMENT_BODY TRUE
J 0
(-3725 3800);
DISPLAY 0.936170 (-3725 3800);
PAINT GREEN (-3725 3800);
DISPLAY INVISIBLE (-3725 3800);
FORCEPROP 2 LAST PATH I137
J 0
(-3800 3975);
DISPLAY 0.787234 (-3800 3975);
PAINT MONO (-3800 3975);
DISPLAY INVISIBLE (-3800 3975);
FORCEADD TAP..6
(-3250 2800);
FORCEPROP 3 LASTPIN (-3200 2800) SIG_NAME M_M_ECC<7>
J 0
(-3190 2810);
DISPLAY 0.659574 (-3190 2810);
PAINT MONO (-3190 2810);
DISPLAY INVISIBLE (-3190 2810);
FORCEPROP 1 LASTPIN (-3200 2800) BN 7
J 0
(-3250 2810);
DISPLAY 0.617021 (-3250 2810);
PAINT PINK (-3250 2810);
FORCEPROP 2 LAST CDS_LIB mstr_standard
J 0
(-3250 2800);
DISPLAY 0.787234 (-3250 2800);
PAINT MONO (-3250 2800);
DISPLAY INVISIBLE (-3250 2800);
FORCEPROP 1 LAST BODY_TYPE PLUMBING
J 0
(-3250 2750);
DISPLAY 1.234043 (-3250 2750);
PAINT GREEN (-3250 2750);
DISPLAY INVISIBLE (-3250 2750);
FORCEPROP 1 LAST HDL_TAP TRUE
J 0
(-2925 2675);
DISPLAY 1.234043 (-2925 2675);
PAINT GREEN (-2925 2675);
DISPLAY INVISIBLE (-2925 2675);
FORCEPROP 1 LAST PATH I138
J 0
(-3250 2800);
DISPLAY 0.936170 (-3250 2800);
PAINT GREEN (-3250 2800);
DISPLAY INVISIBLE (-3250 2800);
FORCEADD TAP..6
(-3250 2850);
FORCEPROP 3 LASTPIN (-3200 2850) SIG_NAME M_M_ECC<6>
J 0
(-3190 2860);
DISPLAY 0.659574 (-3190 2860);
PAINT MONO (-3190 2860);
DISPLAY INVISIBLE (-3190 2860);
FORCEPROP 1 LASTPIN (-3200 2850) BN 6
J 0
(-3250 2860);
DISPLAY 0.617021 (-3250 2860);
PAINT PINK (-3250 2860);
FORCEPROP 2 LAST CDS_LIB mstr_standard
J 0
(-3250 2850);
DISPLAY 0.787234 (-3250 2850);
PAINT MONO (-3250 2850);
DISPLAY INVISIBLE (-3250 2850);
FORCEPROP 1 LAST BODY_TYPE PLUMBING
J 0
(-3250 2800);
DISPLAY 1.234043 (-3250 2800);
PAINT GREEN (-3250 2800);
DISPLAY INVISIBLE (-3250 2800);
FORCEPROP 1 LAST HDL_TAP TRUE
J 0
(-2925 2725);
DISPLAY 1.234043 (-2925 2725);
PAINT GREEN (-2925 2725);
DISPLAY INVISIBLE (-2925 2725);
FORCEPROP 1 LAST PATH I139
J 0
(-3250 2850);
DISPLAY 0.936170 (-3250 2850);
PAINT GREEN (-3250 2850);
DISPLAY INVISIBLE (-3250 2850);
FORCEADD TAP..6
R 2
(900 4300);
FORCEPROP 3 LASTPIN (850 4300) SIG_NAME M_M_DQS_DN<9>
J 0
(860 4310);
DISPLAY 0.659574 (860 4310);
PAINT MONO (860 4310);
DISPLAY INVISIBLE (860 4310);
FORCEPROP 1 LASTPIN (850 4300) BN 9
J 2
(900 4310);
DISPLAY 0.617021 (900 4310);
PAINT PINK (900 4310);
FORCEPROP 2 LAST CDS_LIB mstr_standard
J 0
(900 4300);
DISPLAY 0.787234 (900 4300);
PAINT MONO (900 4300);
DISPLAY INVISIBLE (900 4300);
FORCEPROP 1 LAST BODY_TYPE PLUMBING
J 2
(900 4250);
DISPLAY 1.234043 (900 4250);
PAINT GREEN (900 4250);
DISPLAY INVISIBLE (900 4250);
FORCEPROP 1 LAST HDL_TAP TRUE
J 2
(575 4175);
DISPLAY 1.234043 (575 4175);
PAINT GREEN (575 4175);
DISPLAY INVISIBLE (575 4175);
FORCEPROP 1 LAST PATH I14
J 2
(900 4300);
DISPLAY 0.936170 (900 4300);
PAINT GREEN (900 4300);
DISPLAY INVISIBLE (900 4300);
FORCEADD TAP..6
(-3250 2750);
FORCEPROP 3 LASTPIN (-3200 2750) SIG_NAME M_M_ECC<4>
J 0
(-3190 2760);
DISPLAY 0.659574 (-3190 2760);
PAINT MONO (-3190 2760);
DISPLAY INVISIBLE (-3190 2760);
FORCEPROP 1 LASTPIN (-3200 2750) BN 4
J 0
(-3250 2760);
DISPLAY 0.617021 (-3250 2760);
PAINT PINK (-3250 2760);
FORCEPROP 2 LAST CDS_LIB mstr_standard
J 0
(-3250 2750);
DISPLAY 0.787234 (-3250 2750);
PAINT MONO (-3250 2750);
DISPLAY INVISIBLE (-3250 2750);
FORCEPROP 1 LAST BODY_TYPE PLUMBING
J 0
(-3250 2700);
DISPLAY 1.234043 (-3250 2700);
PAINT GREEN (-3250 2700);
DISPLAY INVISIBLE (-3250 2700);
FORCEPROP 1 LAST HDL_TAP TRUE
J 0
(-2925 2625);
DISPLAY 1.234043 (-2925 2625);
PAINT GREEN (-2925 2625);
DISPLAY INVISIBLE (-2925 2625);
FORCEPROP 1 LAST PATH I140
J 0
(-3250 2750);
DISPLAY 0.936170 (-3250 2750);
PAINT GREEN (-3250 2750);
DISPLAY INVISIBLE (-3250 2750);
FORCEADD TAP..6
(-3250 2700);
FORCEPROP 3 LASTPIN (-3200 2700) SIG_NAME M_M_ECC<5>
J 0
(-3190 2710);
DISPLAY 0.659574 (-3190 2710);
PAINT MONO (-3190 2710);
DISPLAY INVISIBLE (-3190 2710);
FORCEPROP 1 LASTPIN (-3200 2700) BN 5
J 0
(-3250 2710);
DISPLAY 0.617021 (-3250 2710);
PAINT PINK (-3250 2710);
FORCEPROP 2 LAST CDS_LIB mstr_standard
J 0
(-3250 2700);
DISPLAY 0.787234 (-3250 2700);
PAINT MONO (-3250 2700);
DISPLAY INVISIBLE (-3250 2700);
FORCEPROP 1 LAST BODY_TYPE PLUMBING
J 0
(-3250 2650);
DISPLAY 1.234043 (-3250 2650);
PAINT GREEN (-3250 2650);
DISPLAY INVISIBLE (-3250 2650);
FORCEPROP 1 LAST HDL_TAP TRUE
J 0
(-2925 2575);
DISPLAY 1.234043 (-2925 2575);
PAINT GREEN (-2925 2575);
DISPLAY INVISIBLE (-2925 2575);
FORCEPROP 1 LAST PATH I141
J 0
(-3250 2700);
DISPLAY 0.936170 (-3250 2700);
PAINT GREEN (-3250 2700);
DISPLAY INVISIBLE (-3250 2700);
FORCEADD TAP..6
(-3250 2650);
FORCEPROP 3 LASTPIN (-3200 2650) SIG_NAME M_M_ECC<2>
J 0
(-3190 2660);
DISPLAY 0.659574 (-3190 2660);
PAINT MONO (-3190 2660);
DISPLAY INVISIBLE (-3190 2660);
FORCEPROP 1 LASTPIN (-3200 2650) BN 2
J 0
(-3250 2660);
DISPLAY 0.617021 (-3250 2660);
PAINT PINK (-3250 2660);
FORCEPROP 2 LAST CDS_LIB mstr_standard
J 0
(-3250 2650);
DISPLAY 0.787234 (-3250 2650);
PAINT MONO (-3250 2650);
DISPLAY INVISIBLE (-3250 2650);
FORCEPROP 1 LAST BODY_TYPE PLUMBING
J 0
(-3250 2600);
DISPLAY 1.234043 (-3250 2600);
PAINT GREEN (-3250 2600);
DISPLAY INVISIBLE (-3250 2600);
FORCEPROP 1 LAST HDL_TAP TRUE
J 0
(-2925 2525);
DISPLAY 1.234043 (-2925 2525);
PAINT GREEN (-2925 2525);
DISPLAY INVISIBLE (-2925 2525);
FORCEPROP 1 LAST PATH I142
J 0
(-3250 2650);
DISPLAY 0.936170 (-3250 2650);
PAINT GREEN (-3250 2650);
DISPLAY INVISIBLE (-3250 2650);
FORCEADD TAP..6
(-3250 2600);
FORCEPROP 3 LASTPIN (-3200 2600) SIG_NAME M_M_ECC<3>
J 0
(-3190 2610);
DISPLAY 0.659574 (-3190 2610);
PAINT MONO (-3190 2610);
DISPLAY INVISIBLE (-3190 2610);
FORCEPROP 1 LASTPIN (-3200 2600) BN 3
J 0
(-3250 2610);
DISPLAY 0.617021 (-3250 2610);
PAINT PINK (-3250 2610);
FORCEPROP 2 LAST CDS_LIB mstr_standard
J 0
(-3250 2600);
DISPLAY 0.787234 (-3250 2600);
PAINT MONO (-3250 2600);
DISPLAY INVISIBLE (-3250 2600);
FORCEPROP 1 LAST BODY_TYPE PLUMBING
J 0
(-3250 2550);
DISPLAY 1.234043 (-3250 2550);
PAINT GREEN (-3250 2550);
DISPLAY INVISIBLE (-3250 2550);
FORCEPROP 1 LAST HDL_TAP TRUE
J 0
(-2925 2475);
DISPLAY 1.234043 (-2925 2475);
PAINT GREEN (-2925 2475);
DISPLAY INVISIBLE (-2925 2475);
FORCEPROP 1 LAST PATH I143
J 0
(-3250 2600);
DISPLAY 0.936170 (-3250 2600);
PAINT GREEN (-3250 2600);
DISPLAY INVISIBLE (-3250 2600);
FORCEADD TAP..6
(-3250 2550);
FORCEPROP 3 LASTPIN (-3200 2550) SIG_NAME M_M_ECC<0>
J 0
(-3190 2560);
DISPLAY 0.659574 (-3190 2560);
PAINT MONO (-3190 2560);
DISPLAY INVISIBLE (-3190 2560);
FORCEPROP 1 LASTPIN (-3200 2550) BN 0
J 0
(-3250 2560);
DISPLAY 0.617021 (-3250 2560);
PAINT PINK (-3250 2560);
FORCEPROP 2 LAST CDS_LIB mstr_standard
J 0
(-3250 2550);
DISPLAY 0.787234 (-3250 2550);
PAINT MONO (-3250 2550);
DISPLAY INVISIBLE (-3250 2550);
FORCEPROP 1 LAST BODY_TYPE PLUMBING
J 0
(-3250 2500);
DISPLAY 1.234043 (-3250 2500);
PAINT GREEN (-3250 2500);
DISPLAY INVISIBLE (-3250 2500);
FORCEPROP 1 LAST HDL_TAP TRUE
J 0
(-2925 2425);
DISPLAY 1.234043 (-2925 2425);
PAINT GREEN (-2925 2425);
DISPLAY INVISIBLE (-2925 2425);
FORCEPROP 1 LAST PATH I144
J 0
(-3250 2550);
DISPLAY 0.936170 (-3250 2550);
PAINT GREEN (-3250 2550);
DISPLAY INVISIBLE (-3250 2550);
FORCEADD TAP..6
(-3250 2500);
FORCEPROP 3 LASTPIN (-3200 2500) SIG_NAME M_M_ECC<1>
J 0
(-3190 2510);
DISPLAY 0.659574 (-3190 2510);
PAINT MONO (-3190 2510);
DISPLAY INVISIBLE (-3190 2510);
FORCEPROP 1 LASTPIN (-3200 2500) BN 1
J 0
(-3250 2510);
DISPLAY 0.617021 (-3250 2510);
PAINT PINK (-3250 2510);
FORCEPROP 2 LAST CDS_LIB mstr_standard
J 0
(-3250 2500);
DISPLAY 0.787234 (-3250 2500);
PAINT MONO (-3250 2500);
DISPLAY INVISIBLE (-3250 2500);
FORCEPROP 1 LAST BODY_TYPE PLUMBING
J 0
(-3250 2450);
DISPLAY 1.234043 (-3250 2450);
PAINT GREEN (-3250 2450);
DISPLAY INVISIBLE (-3250 2450);
FORCEPROP 1 LAST HDL_TAP TRUE
J 0
(-2925 2375);
DISPLAY 1.234043 (-2925 2375);
PAINT GREEN (-2925 2375);
DISPLAY INVISIBLE (-2925 2375);
FORCEPROP 1 LAST PATH I145
J 0
(-3250 2500);
DISPLAY 0.936170 (-3250 2500);
PAINT GREEN (-3250 2500);
DISPLAY INVISIBLE (-3250 2500);
FORCEADD OFFPAGE..1
(-3850 2850);
FORCEPROP 2 LAST $XR1 88 
J 0
(-4191 2850);
DISPLAY 0.638298 (-4191 2850);
PAINT MONO (-4191 2850);
FORCEPROP 2 LAST $XR0 62 
J 0
(-4101 2850);
DISPLAY 0.638298 (-4101 2850);
PAINT MONO (-4101 2850);
FORCEPROP 2 LAST CDS_LIB mstr_standard
J 0
(-3850 2850);
DISPLAY 0.787234 (-3850 2850);
PAINT MONO (-3850 2850);
DISPLAY INVISIBLE (-3850 2850);
FORCEPROP 1 LAST OFFPAGE TRUE
J 0
(-3525 2725);
DISPLAY 0.936170 (-3525 2725);
PAINT GREEN (-3525 2725);
DISPLAY INVISIBLE (-3525 2725);
FORCEPROP 1 LAST COMMENT_BODY TRUE
J 0
(-3725 2750);
DISPLAY 0.936170 (-3725 2750);
PAINT GREEN (-3725 2750);
DISPLAY INVISIBLE (-3725 2750);
FORCEPROP 2 LAST PATH I146
J 0
(-3800 2925);
DISPLAY 0.787234 (-3800 2925);
PAINT MONO (-3800 2925);
DISPLAY INVISIBLE (-3800 2925);
FORCEADD OFFPAGE..1
(-3850 2800);
FORCEPROP 2 LAST $XR5 88 
J 0
(-4551 2800);
DISPLAY 0.638298 (-4551 2800);
PAINT MONO (-4551 2800);
FORCEPROP 2 LAST $XR4 86 
J 0
(-4461 2800);
DISPLAY 0.638298 (-4461 2800);
PAINT MONO (-4461 2800);
FORCEPROP 2 LAST $XR3 85 
J 0
(-4371 2800);
DISPLAY 0.638298 (-4371 2800);
PAINT MONO (-4371 2800);
FORCEPROP 2 LAST $XR2 84 
J 0
(-4281 2800);
DISPLAY 0.638298 (-4281 2800);
PAINT MONO (-4281 2800);
FORCEPROP 2 LAST $XR1 83 
J 0
(-4191 2800);
DISPLAY 0.638298 (-4191 2800);
PAINT MONO (-4191 2800);
FORCEPROP 2 LAST $XR0 55 
J 0
(-4101 2800);
DISPLAY 0.638298 (-4101 2800);
PAINT MONO (-4101 2800);
FORCEPROP 2 LAST CDS_LIB mstr_standard
J 0
(-3850 2800);
DISPLAY 0.787234 (-3850 2800);
PAINT MONO (-3850 2800);
DISPLAY INVISIBLE (-3850 2800);
FORCEPROP 1 LAST OFFPAGE TRUE
J 0
(-3525 2675);
DISPLAY 0.936170 (-3525 2675);
PAINT GREEN (-3525 2675);
DISPLAY INVISIBLE (-3525 2675);
FORCEPROP 1 LAST COMMENT_BODY TRUE
J 0
(-3725 2700);
DISPLAY 0.936170 (-3725 2700);
PAINT GREEN (-3725 2700);
DISPLAY INVISIBLE (-3725 2700);
FORCEPROP 2 LAST PATH I147
J 0
(-3800 2875);
DISPLAY 0.787234 (-3800 2875);
PAINT MONO (-3800 2875);
DISPLAY INVISIBLE (-3800 2875);
FORCEADD OFFPAGE..5
(-4075 2250);
FORCEPROP 2 LAST $XR1 62 
J 0
(-4389 2250);
DISPLAY 0.638298 (-4389 2250);
PAINT MONO (-4389 2250);
FORCEPROP 2 LAST $XR0 88 
J 0
(-4299 2250);
DISPLAY 0.638298 (-4299 2250);
PAINT MONO (-4299 2250);
FORCEPROP 2 LAST CDS_LIB mstr_standard
J 0
(-4075 2250);
DISPLAY 0.787234 (-4075 2250);
PAINT MONO (-4075 2250);
DISPLAY INVISIBLE (-4075 2250);
FORCEPROP 1 LAST OFFPAGE TRUE
J 0
(-3750 2125);
DISPLAY 1.404255 (-3750 2125);
PAINT GREEN (-3750 2125);
DISPLAY INVISIBLE (-3750 2125);
FORCEPROP 1 LAST COMMENT_BODY TRUE
J 0
(-3975 2175);
DISPLAY 1.404255 (-3975 2175);
PAINT GREEN (-3975 2175);
DISPLAY INVISIBLE (-3975 2175);
FORCEPROP 2 LAST PATH I148
J 0
(-4025 2325);
DISPLAY 0.787234 (-4025 2325);
PAINT MONO (-4025 2325);
DISPLAY INVISIBLE (-4025 2325);
FORCEADD OFFPAGE..1
(-4050 2200);
FORCEPROP 2 LAST $XR1 88 
J 0
(-4391 2200);
DISPLAY 0.638298 (-4391 2200);
PAINT MONO (-4391 2200);
FORCEPROP 2 LAST $XR0 62 
J 0
(-4301 2200);
DISPLAY 0.638298 (-4301 2200);
PAINT MONO (-4301 2200);
FORCEPROP 2 LAST CDS_LIB mstr_standard
J 0
(-4050 2200);
DISPLAY 0.787234 (-4050 2200);
PAINT MONO (-4050 2200);
DISPLAY INVISIBLE (-4050 2200);
FORCEPROP 1 LAST OFFPAGE TRUE
J 0
(-3725 2075);
DISPLAY 0.936170 (-3725 2075);
PAINT GREEN (-3725 2075);
DISPLAY INVISIBLE (-3725 2075);
FORCEPROP 1 LAST COMMENT_BODY TRUE
J 0
(-3925 2100);
DISPLAY 0.936170 (-3925 2100);
PAINT GREEN (-3925 2100);
DISPLAY INVISIBLE (-3925 2100);
FORCEPROP 2 LAST PATH I149
J 0
(-4000 2275);
DISPLAY 0.787234 (-4000 2275);
PAINT MONO (-4000 2275);
DISPLAY INVISIBLE (-4000 2275);
FORCEADD TAP..6
R 2
(900 4200);
FORCEPROP 3 LASTPIN (850 4200) SIG_NAME M_M_DQS_DN<8>
J 0
(860 4210);
DISPLAY 0.659574 (860 4210);
PAINT MONO (860 4210);
DISPLAY INVISIBLE (860 4210);
FORCEPROP 1 LASTPIN (850 4200) BN 8
J 2
(900 4210);
DISPLAY 0.617021 (900 4210);
PAINT PINK (900 4210);
FORCEPROP 2 LAST CDS_LIB mstr_standard
J 0
(900 4200);
DISPLAY 0.787234 (900 4200);
PAINT MONO (900 4200);
DISPLAY INVISIBLE (900 4200);
FORCEPROP 1 LAST BODY_TYPE PLUMBING
J 2
(900 4150);
DISPLAY 1.234043 (900 4150);
PAINT GREEN (900 4150);
DISPLAY INVISIBLE (900 4150);
FORCEPROP 1 LAST HDL_TAP TRUE
J 2
(575 4075);
DISPLAY 1.234043 (575 4075);
PAINT GREEN (575 4075);
DISPLAY INVISIBLE (575 4075);
FORCEPROP 1 LAST PATH I15
J 2
(900 4200);
DISPLAY 0.936170 (900 4200);
PAINT GREEN (900 4200);
DISPLAY INVISIBLE (900 4200);
FORCEADD OFFPAGE..6
(-3850 2900);
FORCEPROP 2 LAST $XR1 88 
J 0
(-4189 2900);
DISPLAY 0.638298 (-4189 2900);
PAINT MONO (-4189 2900);
FORCEPROP 2 LAST $XR0 62 
J 0
(-4099 2900);
DISPLAY 0.638298 (-4099 2900);
PAINT MONO (-4099 2900);
FORCEPROP 2 LAST CDS_LIB mstr_standard
J 0
(-3850 2900);
DISPLAY 0.787234 (-3850 2900);
PAINT MONO (-3850 2900);
DISPLAY INVISIBLE (-3850 2900);
FORCEPROP 1 LAST OFFPAGE TRUE
J 0
(-3525 2775);
DISPLAY 0.936170 (-3525 2775);
PAINT GREEN (-3525 2775);
DISPLAY INVISIBLE (-3525 2775);
FORCEPROP 1 LAST COMMENT_BODY TRUE
J 0
(-3750 2825);
DISPLAY 0.936170 (-3750 2825);
PAINT GREEN (-3750 2825);
DISPLAY INVISIBLE (-3750 2825);
FORCEPROP 2 LAST PATH I150
J 0
(-3800 2975);
DISPLAY 0.787234 (-3800 2975);
PAINT MONO (-3800 2975);
DISPLAY INVISIBLE (-3800 2975);
FORCEADD TAP..6
(-3250 3700);
FORCEPROP 3 LASTPIN (-3200 3700) SIG_NAME M_M_CLK_DP<1>
J 0
(-3190 3710);
DISPLAY 0.659574 (-3190 3710);
PAINT MONO (-3190 3710);
DISPLAY INVISIBLE (-3190 3710);
FORCEPROP 1 LASTPIN (-3200 3700) BN 1
J 0
(-3250 3710);
DISPLAY 0.617021 (-3250 3710);
PAINT PINK (-3250 3710);
FORCEPROP 2 LAST CDS_LIB mstr_standard
J 0
(-3250 3700);
DISPLAY 0.787234 (-3250 3700);
PAINT MONO (-3250 3700);
DISPLAY INVISIBLE (-3250 3700);
FORCEPROP 1 LAST BODY_TYPE PLUMBING
J 0
(-3250 3650);
DISPLAY 1.234043 (-3250 3650);
PAINT GREEN (-3250 3650);
DISPLAY INVISIBLE (-3250 3650);
FORCEPROP 1 LAST HDL_TAP TRUE
J 0
(-2925 3575);
DISPLAY 1.234043 (-2925 3575);
PAINT GREEN (-2925 3575);
DISPLAY INVISIBLE (-2925 3575);
FORCEPROP 1 LAST PATH I152
J 0
(-3250 3700);
DISPLAY 0.936170 (-3250 3700);
PAINT GREEN (-3250 3700);
DISPLAY INVISIBLE (-3250 3700);
FORCEADD TAP..6
(-3250 3600);
FORCEPROP 3 LASTPIN (-3200 3600) SIG_NAME M_M_CLK_DP<0>
J 0
(-3190 3610);
DISPLAY 0.659574 (-3190 3610);
PAINT MONO (-3190 3610);
DISPLAY INVISIBLE (-3190 3610);
FORCEPROP 1 LASTPIN (-3200 3600) BN 0
J 0
(-3250 3610);
DISPLAY 0.617021 (-3250 3610);
PAINT PINK (-3250 3610);
FORCEPROP 2 LAST CDS_LIB mstr_standard
J 0
(-3250 3600);
DISPLAY 0.787234 (-3250 3600);
PAINT MONO (-3250 3600);
DISPLAY INVISIBLE (-3250 3600);
FORCEPROP 1 LAST BODY_TYPE PLUMBING
J 0
(-3250 3550);
DISPLAY 1.234043 (-3250 3550);
PAINT GREEN (-3250 3550);
DISPLAY INVISIBLE (-3250 3550);
FORCEPROP 1 LAST HDL_TAP TRUE
J 0
(-2925 3475);
DISPLAY 1.234043 (-2925 3475);
PAINT GREEN (-2925 3475);
DISPLAY INVISIBLE (-2925 3475);
FORCEPROP 1 LAST PATH I153
J 0
(-3250 3600);
DISPLAY 0.936170 (-3250 3600);
PAINT GREEN (-3250 3600);
DISPLAY INVISIBLE (-3250 3600);
FORCEADD TAP..6
(-3450 3650);
FORCEPROP 3 LASTPIN (-3400 3650) SIG_NAME M_M_CLK_DN<1>
J 0
(-3390 3660);
DISPLAY 0.659574 (-3390 3660);
PAINT MONO (-3390 3660);
DISPLAY INVISIBLE (-3390 3660);
FORCEPROP 1 LASTPIN (-3400 3650) BN 1
J 0
(-3450 3660);
DISPLAY 0.617021 (-3450 3660);
PAINT PINK (-3450 3660);
FORCEPROP 2 LAST CDS_LIB mstr_standard
J 0
(-3450 3650);
DISPLAY 0.787234 (-3450 3650);
PAINT MONO (-3450 3650);
DISPLAY INVISIBLE (-3450 3650);
FORCEPROP 1 LAST BODY_TYPE PLUMBING
J 0
(-3450 3600);
DISPLAY 1.234043 (-3450 3600);
PAINT GREEN (-3450 3600);
DISPLAY INVISIBLE (-3450 3600);
FORCEPROP 1 LAST HDL_TAP TRUE
J 0
(-3125 3525);
DISPLAY 1.234043 (-3125 3525);
PAINT GREEN (-3125 3525);
DISPLAY INVISIBLE (-3125 3525);
FORCEPROP 1 LAST PATH I154
J 0
(-3450 3650);
DISPLAY 0.936170 (-3450 3650);
PAINT GREEN (-3450 3650);
DISPLAY INVISIBLE (-3450 3650);
FORCEADD TAP..6
(-3450 3550);
FORCEPROP 3 LASTPIN (-3400 3550) SIG_NAME M_M_CLK_DN<0>
J 0
(-3390 3560);
DISPLAY 0.659574 (-3390 3560);
PAINT MONO (-3390 3560);
DISPLAY INVISIBLE (-3390 3560);
FORCEPROP 1 LASTPIN (-3400 3550) BN 0
J 0
(-3450 3560);
DISPLAY 0.617021 (-3450 3560);
PAINT PINK (-3450 3560);
FORCEPROP 2 LAST CDS_LIB mstr_standard
J 0
(-3450 3550);
DISPLAY 0.787234 (-3450 3550);
PAINT MONO (-3450 3550);
DISPLAY INVISIBLE (-3450 3550);
FORCEPROP 1 LAST BODY_TYPE PLUMBING
J 0
(-3450 3500);
DISPLAY 1.234043 (-3450 3500);
PAINT GREEN (-3450 3500);
DISPLAY INVISIBLE (-3450 3500);
FORCEPROP 1 LAST HDL_TAP TRUE
J 0
(-3125 3425);
DISPLAY 1.234043 (-3125 3425);
PAINT GREEN (-3125 3425);
DISPLAY INVISIBLE (-3125 3425);
FORCEPROP 1 LAST PATH I155
J 0
(-3450 3550);
DISPLAY 0.936170 (-3450 3550);
PAINT GREEN (-3450 3550);
DISPLAY INVISIBLE (-3450 3550);
FORCEADD OFFPAGE..1
(-3850 3725);
FORCEPROP 2 LAST $XR1 88 
J 0
(-4191 3725);
DISPLAY 0.638298 (-4191 3725);
PAINT MONO (-4191 3725);
FORCEPROP 2 LAST $XR0 62 
J 0
(-4101 3725);
DISPLAY 0.638298 (-4101 3725);
PAINT MONO (-4101 3725);
FORCEPROP 2 LAST CDS_LIB mstr_standard
J 0
(-3850 3725);
DISPLAY 0.787234 (-3850 3725);
PAINT MONO (-3850 3725);
DISPLAY INVISIBLE (-3850 3725);
FORCEPROP 1 LAST OFFPAGE TRUE
J 0
(-3525 3600);
DISPLAY 0.936170 (-3525 3600);
PAINT GREEN (-3525 3600);
DISPLAY INVISIBLE (-3525 3600);
FORCEPROP 1 LAST COMMENT_BODY TRUE
J 0
(-3725 3625);
DISPLAY 0.936170 (-3725 3625);
PAINT GREEN (-3725 3625);
DISPLAY INVISIBLE (-3725 3625);
FORCEPROP 2 LAST PATH I156
J 0
(-3800 3800);
DISPLAY 0.787234 (-3800 3800);
PAINT MONO (-3800 3800);
DISPLAY INVISIBLE (-3800 3800);
FORCEADD OFFPAGE..1
(-3850 3775);
FORCEPROP 2 LAST $XR1 88 
J 0
(-4191 3775);
DISPLAY 0.638298 (-4191 3775);
PAINT MONO (-4191 3775);
FORCEPROP 2 LAST $XR0 62 
J 0
(-4101 3775);
DISPLAY 0.638298 (-4101 3775);
PAINT MONO (-4101 3775);
FORCEPROP 2 LAST CDS_LIB mstr_standard
J 0
(-3850 3775);
DISPLAY 0.787234 (-3850 3775);
PAINT MONO (-3850 3775);
DISPLAY INVISIBLE (-3850 3775);
FORCEPROP 1 LAST OFFPAGE TRUE
J 0
(-3525 3650);
DISPLAY 0.936170 (-3525 3650);
PAINT GREEN (-3525 3650);
DISPLAY INVISIBLE (-3525 3650);
FORCEPROP 1 LAST COMMENT_BODY TRUE
J 0
(-3725 3675);
DISPLAY 0.936170 (-3725 3675);
PAINT GREEN (-3725 3675);
DISPLAY INVISIBLE (-3725 3675);
FORCEPROP 2 LAST PATH I157
J 0
(-3800 3850);
DISPLAY 0.787234 (-3800 3850);
PAINT MONO (-3800 3850);
DISPLAY INVISIBLE (-3800 3850);
FORCEADD TAP..6
(-3250 3400);
FORCEPROP 3 LASTPIN (-3200 3400) SIG_NAME M_M_CS_N<3>
J 0
(-3190 3410);
DISPLAY 0.659574 (-3190 3410);
PAINT MONO (-3190 3410);
DISPLAY INVISIBLE (-3190 3410);
FORCEPROP 1 LASTPIN (-3200 3400) BN 3
J 0
(-3250 3410);
DISPLAY 0.617021 (-3250 3410);
PAINT PINK (-3250 3410);
FORCEPROP 2 LAST CDS_LIB mstr_standard
J 0
(-3250 3400);
DISPLAY 0.787234 (-3250 3400);
PAINT MONO (-3250 3400);
DISPLAY INVISIBLE (-3250 3400);
FORCEPROP 1 LAST BODY_TYPE PLUMBING
J 0
(-3250 3350);
DISPLAY 1.234043 (-3250 3350);
PAINT GREEN (-3250 3350);
DISPLAY INVISIBLE (-3250 3350);
FORCEPROP 1 LAST HDL_TAP TRUE
J 0
(-2925 3275);
DISPLAY 1.234043 (-2925 3275);
PAINT GREEN (-2925 3275);
DISPLAY INVISIBLE (-2925 3275);
FORCEPROP 1 LAST PATH I158
J 0
(-3250 3400);
DISPLAY 0.936170 (-3250 3400);
PAINT GREEN (-3250 3400);
DISPLAY INVISIBLE (-3250 3400);
FORCEADD TAP..6
(-3250 3350);
FORCEPROP 3 LASTPIN (-3200 3350) SIG_NAME M_M_CS_N<2>
J 0
(-3190 3360);
DISPLAY 0.659574 (-3190 3360);
PAINT MONO (-3190 3360);
DISPLAY INVISIBLE (-3190 3360);
FORCEPROP 1 LASTPIN (-3200 3350) BN 2
J 0
(-3250 3360);
DISPLAY 0.617021 (-3250 3360);
PAINT PINK (-3250 3360);
FORCEPROP 2 LAST CDS_LIB mstr_standard
J 0
(-3250 3350);
DISPLAY 0.787234 (-3250 3350);
PAINT MONO (-3250 3350);
DISPLAY INVISIBLE (-3250 3350);
FORCEPROP 1 LAST BODY_TYPE PLUMBING
J 0
(-3250 3300);
DISPLAY 1.234043 (-3250 3300);
PAINT GREEN (-3250 3300);
DISPLAY INVISIBLE (-3250 3300);
FORCEPROP 1 LAST HDL_TAP TRUE
J 0
(-2925 3225);
DISPLAY 1.234043 (-2925 3225);
PAINT GREEN (-2925 3225);
DISPLAY INVISIBLE (-2925 3225);
FORCEPROP 1 LAST PATH I159
J 0
(-3250 3350);
DISPLAY 0.936170 (-3250 3350);
PAINT GREEN (-3250 3350);
DISPLAY INVISIBLE (-3250 3350);
FORCEADD TAP..6
R 2
(900 4100);
FORCEPROP 3 LASTPIN (850 4100) SIG_NAME M_M_DQS_DN<7>
J 0
(860 4110);
DISPLAY 0.659574 (860 4110);
PAINT MONO (860 4110);
DISPLAY INVISIBLE (860 4110);
FORCEPROP 1 LASTPIN (850 4100) BN 7
J 2
(900 4110);
DISPLAY 0.617021 (900 4110);
PAINT PINK (900 4110);
FORCEPROP 2 LAST CDS_LIB mstr_standard
J 0
(900 4100);
DISPLAY 0.787234 (900 4100);
PAINT MONO (900 4100);
DISPLAY INVISIBLE (900 4100);
FORCEPROP 1 LAST BODY_TYPE PLUMBING
J 2
(900 4050);
DISPLAY 1.234043 (900 4050);
PAINT GREEN (900 4050);
DISPLAY INVISIBLE (900 4050);
FORCEPROP 1 LAST HDL_TAP TRUE
J 2
(575 3975);
DISPLAY 1.234043 (575 3975);
PAINT GREEN (575 3975);
DISPLAY INVISIBLE (575 3975);
FORCEPROP 1 LAST PATH I16
J 2
(900 4100);
DISPLAY 0.936170 (900 4100);
PAINT GREEN (900 4100);
DISPLAY INVISIBLE (900 4100);
FORCEADD TAP..6
(-3250 3300);
FORCEPROP 3 LASTPIN (-3200 3300) SIG_NAME M_M_CS_N<1>
J 0
(-3190 3310);
DISPLAY 0.659574 (-3190 3310);
PAINT MONO (-3190 3310);
DISPLAY INVISIBLE (-3190 3310);
FORCEPROP 1 LASTPIN (-3200 3300) BN 1
J 0
(-3250 3310);
DISPLAY 0.617021 (-3250 3310);
PAINT PINK (-3250 3310);
FORCEPROP 2 LAST CDS_LIB mstr_standard
J 0
(-3250 3300);
DISPLAY 0.787234 (-3250 3300);
PAINT MONO (-3250 3300);
DISPLAY INVISIBLE (-3250 3300);
FORCEPROP 1 LAST BODY_TYPE PLUMBING
J 0
(-3250 3250);
DISPLAY 1.234043 (-3250 3250);
PAINT GREEN (-3250 3250);
DISPLAY INVISIBLE (-3250 3250);
FORCEPROP 1 LAST HDL_TAP TRUE
J 0
(-2925 3175);
DISPLAY 1.234043 (-2925 3175);
PAINT GREEN (-2925 3175);
DISPLAY INVISIBLE (-2925 3175);
FORCEPROP 1 LAST PATH I160
J 0
(-3250 3300);
DISPLAY 0.936170 (-3250 3300);
PAINT GREEN (-3250 3300);
DISPLAY INVISIBLE (-3250 3300);
FORCEADD TAP..6
(-3250 3250);
FORCEPROP 3 LASTPIN (-3200 3250) SIG_NAME M_M_CS_N<0>
J 0
(-3190 3260);
DISPLAY 0.659574 (-3190 3260);
PAINT MONO (-3190 3260);
DISPLAY INVISIBLE (-3190 3260);
FORCEPROP 1 LASTPIN (-3200 3250) BN 0
J 0
(-3250 3260);
DISPLAY 0.617021 (-3250 3260);
PAINT PINK (-3250 3260);
FORCEPROP 2 LAST CDS_LIB mstr_standard
J 0
(-3250 3250);
DISPLAY 0.787234 (-3250 3250);
PAINT MONO (-3250 3250);
DISPLAY INVISIBLE (-3250 3250);
FORCEPROP 1 LAST BODY_TYPE PLUMBING
J 0
(-3250 3200);
DISPLAY 1.234043 (-3250 3200);
PAINT GREEN (-3250 3200);
DISPLAY INVISIBLE (-3250 3200);
FORCEPROP 1 LAST HDL_TAP TRUE
J 0
(-2925 3125);
DISPLAY 1.234043 (-2925 3125);
PAINT GREEN (-2925 3125);
DISPLAY INVISIBLE (-2925 3125);
FORCEPROP 1 LAST PATH I161
J 0
(-3250 3250);
DISPLAY 0.936170 (-3250 3250);
PAINT GREEN (-3250 3250);
DISPLAY INVISIBLE (-3250 3250);
FORCEADD OFFPAGE..1
(-3850 3450);
FORCEPROP 2 LAST $XR1 88 
J 0
(-4191 3450);
DISPLAY 0.638298 (-4191 3450);
PAINT MONO (-4191 3450);
FORCEPROP 2 LAST $XR0 62 
J 0
(-4101 3450);
DISPLAY 0.638298 (-4101 3450);
PAINT MONO (-4101 3450);
FORCEPROP 2 LAST CDS_LIB mstr_standard
J 0
(-3850 3450);
DISPLAY 0.787234 (-3850 3450);
PAINT MONO (-3850 3450);
DISPLAY INVISIBLE (-3850 3450);
FORCEPROP 1 LAST OFFPAGE TRUE
J 0
(-3525 3325);
DISPLAY 0.936170 (-3525 3325);
PAINT GREEN (-3525 3325);
DISPLAY INVISIBLE (-3525 3325);
FORCEPROP 1 LAST COMMENT_BODY TRUE
J 0
(-3725 3350);
DISPLAY 0.936170 (-3725 3350);
PAINT GREEN (-3725 3350);
DISPLAY INVISIBLE (-3725 3350);
FORCEPROP 2 LAST PATH I162
J 0
(-3800 3525);
DISPLAY 0.787234 (-3800 3525);
PAINT MONO (-3800 3525);
DISPLAY INVISIBLE (-3800 3525);
FORCEADD TAP..6
(-3250 3150);
FORCEPROP 3 LASTPIN (-3200 3150) SIG_NAME M_M_CKE<1>
J 0
(-3190 3160);
DISPLAY 0.659574 (-3190 3160);
PAINT MONO (-3190 3160);
DISPLAY INVISIBLE (-3190 3160);
FORCEPROP 1 LASTPIN (-3200 3150) BN 1
J 0
(-3250 3160);
DISPLAY 0.617021 (-3250 3160);
PAINT PINK (-3250 3160);
FORCEPROP 2 LAST CDS_LIB mstr_standard
J 0
(-3250 3150);
DISPLAY 0.787234 (-3250 3150);
PAINT MONO (-3250 3150);
DISPLAY INVISIBLE (-3250 3150);
FORCEPROP 1 LAST BODY_TYPE PLUMBING
J 0
(-3250 3100);
DISPLAY 1.234043 (-3250 3100);
PAINT GREEN (-3250 3100);
DISPLAY INVISIBLE (-3250 3100);
FORCEPROP 1 LAST HDL_TAP TRUE
J 0
(-2925 3025);
DISPLAY 1.234043 (-2925 3025);
PAINT GREEN (-2925 3025);
DISPLAY INVISIBLE (-2925 3025);
FORCEPROP 1 LAST PATH I163
J 0
(-3250 3150);
DISPLAY 0.936170 (-3250 3150);
PAINT GREEN (-3250 3150);
DISPLAY INVISIBLE (-3250 3150);
FORCEADD TAP..6
(-3250 3100);
FORCEPROP 3 LASTPIN (-3200 3100) SIG_NAME M_M_CKE<0>
J 0
(-3190 3110);
DISPLAY 0.659574 (-3190 3110);
PAINT MONO (-3190 3110);
DISPLAY INVISIBLE (-3190 3110);
FORCEPROP 1 LASTPIN (-3200 3100) BN 0
J 0
(-3250 3110);
DISPLAY 0.617021 (-3250 3110);
PAINT PINK (-3250 3110);
FORCEPROP 2 LAST CDS_LIB mstr_standard
J 0
(-3250 3100);
DISPLAY 0.787234 (-3250 3100);
PAINT MONO (-3250 3100);
DISPLAY INVISIBLE (-3250 3100);
FORCEPROP 1 LAST BODY_TYPE PLUMBING
J 0
(-3250 3050);
DISPLAY 1.234043 (-3250 3050);
PAINT GREEN (-3250 3050);
DISPLAY INVISIBLE (-3250 3050);
FORCEPROP 1 LAST HDL_TAP TRUE
J 0
(-2925 2975);
DISPLAY 1.234043 (-2925 2975);
PAINT GREEN (-2925 2975);
DISPLAY INVISIBLE (-2925 2975);
FORCEPROP 1 LAST PATH I164
J 0
(-3250 3100);
DISPLAY 0.936170 (-3250 3100);
PAINT GREEN (-3250 3100);
DISPLAY INVISIBLE (-3250 3100);
FORCEADD TAP..6
(-3250 3000);
FORCEPROP 3 LASTPIN (-3200 3000) SIG_NAME M_M_ODT<1>
J 0
(-3190 3010);
DISPLAY 0.659574 (-3190 3010);
PAINT MONO (-3190 3010);
DISPLAY INVISIBLE (-3190 3010);
FORCEPROP 1 LASTPIN (-3200 3000) BN 1
J 0
(-3250 3010);
DISPLAY 0.617021 (-3250 3010);
PAINT PINK (-3250 3010);
FORCEPROP 2 LAST CDS_LIB mstr_standard
J 0
(-3250 3000);
DISPLAY 0.787234 (-3250 3000);
PAINT MONO (-3250 3000);
DISPLAY INVISIBLE (-3250 3000);
FORCEPROP 1 LAST BODY_TYPE PLUMBING
J 0
(-3250 2950);
DISPLAY 1.234043 (-3250 2950);
PAINT GREEN (-3250 2950);
DISPLAY INVISIBLE (-3250 2950);
FORCEPROP 1 LAST HDL_TAP TRUE
J 0
(-2925 2875);
DISPLAY 1.234043 (-2925 2875);
PAINT GREEN (-2925 2875);
DISPLAY INVISIBLE (-2925 2875);
FORCEPROP 1 LAST PATH I165
J 0
(-3250 3000);
DISPLAY 0.936170 (-3250 3000);
PAINT GREEN (-3250 3000);
DISPLAY INVISIBLE (-3250 3000);
FORCEADD TAP..6
(-3250 2950);
FORCEPROP 3 LASTPIN (-3200 2950) SIG_NAME M_M_ODT<0>
J 0
(-3190 2960);
DISPLAY 0.659574 (-3190 2960);
PAINT MONO (-3190 2960);
DISPLAY INVISIBLE (-3190 2960);
FORCEPROP 1 LASTPIN (-3200 2950) BN 0
J 0
(-3250 2960);
DISPLAY 0.617021 (-3250 2960);
PAINT PINK (-3250 2960);
FORCEPROP 2 LAST CDS_LIB mstr_standard
J 0
(-3250 2950);
DISPLAY 0.787234 (-3250 2950);
PAINT MONO (-3250 2950);
DISPLAY INVISIBLE (-3250 2950);
FORCEPROP 1 LAST BODY_TYPE PLUMBING
J 0
(-3250 2900);
DISPLAY 1.234043 (-3250 2900);
PAINT GREEN (-3250 2900);
DISPLAY INVISIBLE (-3250 2900);
FORCEPROP 1 LAST HDL_TAP TRUE
J 0
(-2925 2825);
DISPLAY 1.234043 (-2925 2825);
PAINT GREEN (-2925 2825);
DISPLAY INVISIBLE (-2925 2825);
FORCEPROP 1 LAST PATH I166
J 0
(-3250 2950);
DISPLAY 0.936170 (-3250 2950);
PAINT GREEN (-3250 2950);
DISPLAY INVISIBLE (-3250 2950);
FORCEADD OFFPAGE..1
(-3850 3100);
FORCEPROP 2 LAST $XR1 88 
J 0
(-4191 3100);
DISPLAY 0.638298 (-4191 3100);
PAINT MONO (-4191 3100);
FORCEPROP 2 LAST $XR0 62 
J 0
(-4101 3100);
DISPLAY 0.638298 (-4101 3100);
PAINT MONO (-4101 3100);
FORCEPROP 2 LAST CDS_LIB mstr_standard
J 0
(-3850 3100);
DISPLAY 0.787234 (-3850 3100);
PAINT MONO (-3850 3100);
DISPLAY INVISIBLE (-3850 3100);
FORCEPROP 1 LAST OFFPAGE TRUE
J 0
(-3525 2975);
DISPLAY 0.936170 (-3525 2975);
PAINT GREEN (-3525 2975);
DISPLAY INVISIBLE (-3525 2975);
FORCEPROP 1 LAST COMMENT_BODY TRUE
J 0
(-3725 3000);
DISPLAY 0.936170 (-3725 3000);
PAINT GREEN (-3725 3000);
DISPLAY INVISIBLE (-3725 3000);
FORCEPROP 2 LAST PATH I167
J 0
(-3800 3175);
DISPLAY 0.787234 (-3800 3175);
PAINT MONO (-3800 3175);
DISPLAY INVISIBLE (-3800 3175);
FORCEADD OFFPAGE..1
(-3850 3225);
FORCEPROP 2 LAST $XR1 88 
J 0
(-4191 3225);
DISPLAY 0.638298 (-4191 3225);
PAINT MONO (-4191 3225);
FORCEPROP 2 LAST $XR0 62 
J 0
(-4101 3225);
DISPLAY 0.638298 (-4101 3225);
PAINT MONO (-4101 3225);
FORCEPROP 2 LAST CDS_LIB mstr_standard
J 0
(-3850 3225);
DISPLAY 0.787234 (-3850 3225);
PAINT MONO (-3850 3225);
DISPLAY INVISIBLE (-3850 3225);
FORCEPROP 1 LAST OFFPAGE TRUE
J 0
(-3525 3100);
DISPLAY 0.936170 (-3525 3100);
PAINT GREEN (-3525 3100);
DISPLAY INVISIBLE (-3525 3100);
FORCEPROP 1 LAST COMMENT_BODY TRUE
J 0
(-3725 3125);
DISPLAY 0.936170 (-3725 3125);
PAINT GREEN (-3725 3125);
DISPLAY INVISIBLE (-3725 3125);
FORCEPROP 2 LAST PATH I168
J 0
(-3800 3300);
DISPLAY 0.787234 (-3800 3300);
PAINT MONO (-3800 3300);
DISPLAY INVISIBLE (-3800 3300);
FORCEADD SCONN288_H44441004..4
(-400 2050);
FORCEPROP 1 LAST LOCATION J1A1
J 0
(-850 3150);
DISPLAY 0.617021 (-850 3150);
PAINT AQUA (-850 3150);
FORCEPROP 1 LAST PART_NUMBER H44441-004
J 0
(-850 1000);
DISPLAY 0.617021 (-850 1000);
PAINT BLUE (-850 1000);
FORCEPROP 1 LAST MATERIAL SCONN
J 0
(-850 3100);
DISPLAY 0.617021 (-850 3100);
PAINT SKYBLUE (-850 3100);
FORCEPROP 2 LASTPIN (-900 2600) $PN 77
J 2
(-910 2610);
DISPLAY 0.617021 (-910 2610);
PAINT ORANGE (-910 2610);
FORCEPROP 2 LASTPIN (-900 2550) $PN 221
J 2
(-910 2560);
DISPLAY 0.617021 (-910 2560);
PAINT ORANGE (-910 2560);
FORCEPROP 2 LASTPIN (-900 2900) $PN 142
J 2
(-910 2910);
DISPLAY 0.617021 (-910 2910);
PAINT ORANGE (-910 2910);
FORCEPROP 2 LASTPIN (-900 2850) $PN 143
J 2
(-910 2860);
DISPLAY 0.617021 (-910 2860);
PAINT ORANGE (-910 2860);
FORCEPROP 2 LASTPIN (-900 2800) $PN 288
J 2
(-910 2810);
DISPLAY 0.617021 (-910 2810);
PAINT ORANGE (-910 2810);
FORCEPROP 2 LASTPIN (-900 2750) $PN 286
J 2
(-910 2760);
DISPLAY 0.617021 (-910 2760);
PAINT ORANGE (-910 2760);
FORCEPROP 2 LASTPIN (-900 2700) $PN 287
J 2
(-910 2710);
DISPLAY 0.617021 (-910 2710);
PAINT ORANGE (-910 2710);
FORCEPROP 2 LASTPIN (-900 2450) $PN 59
J 2
(-910 2460);
DISPLAY 0.617021 (-910 2460);
PAINT ORANGE (-910 2460);
FORCEPROP 2 LASTPIN (-900 2400) $PN 61
J 2
(-910 2410);
DISPLAY 0.617021 (-910 2410);
PAINT ORANGE (-910 2410);
FORCEPROP 2 LASTPIN (-900 2350) $PN 64
J 2
(-910 2360);
DISPLAY 0.617021 (-910 2360);
PAINT ORANGE (-910 2360);
FORCEPROP 2 LASTPIN (-900 2300) $PN 67
J 2
(-910 2310);
DISPLAY 0.617021 (-910 2310);
PAINT ORANGE (-910 2310);
FORCEPROP 2 LASTPIN (-900 2250) $PN 70
J 2
(-910 2260);
DISPLAY 0.617021 (-910 2260);
PAINT ORANGE (-910 2260);
FORCEPROP 2 LASTPIN (-900 2200) $PN 73
J 2
(-910 2210);
DISPLAY 0.617021 (-910 2210);
PAINT ORANGE (-910 2210);
FORCEPROP 2 LASTPIN (-900 2150) $PN 76
J 2
(-910 2160);
DISPLAY 0.617021 (-910 2160);
PAINT ORANGE (-910 2160);
FORCEPROP 2 LASTPIN (-900 2100) $PN 80
J 2
(-910 2110);
DISPLAY 0.617021 (-910 2110);
PAINT ORANGE (-910 2110);
FORCEPROP 2 LASTPIN (-900 2050) $PN 83
J 2
(-910 2060);
DISPLAY 0.617021 (-910 2060);
PAINT ORANGE (-910 2060);
FORCEPROP 2 LASTPIN (-900 2000) $PN 85
J 2
(-910 2010);
DISPLAY 0.617021 (-910 2010);
PAINT ORANGE (-910 2010);
FORCEPROP 2 LASTPIN (-900 1950) $PN 88
J 2
(-910 1960);
DISPLAY 0.617021 (-910 1960);
PAINT ORANGE (-910 1960);
FORCEPROP 2 LASTPIN (-900 1900) $PN 90
J 2
(-910 1910);
DISPLAY 0.617021 (-910 1910);
PAINT ORANGE (-910 1910);
FORCEPROP 2 LASTPIN (-900 1850) $PN 92
J 2
(-910 1860);
DISPLAY 0.617021 (-910 1860);
PAINT ORANGE (-910 1860);
FORCEPROP 2 LASTPIN (-900 1800) $PN 204
J 2
(-910 1810);
DISPLAY 0.617021 (-910 1810);
PAINT ORANGE (-910 1810);
FORCEPROP 2 LASTPIN (-900 1750) $PN 206
J 2
(-910 1760);
DISPLAY 0.617021 (-910 1760);
PAINT ORANGE (-910 1760);
FORCEPROP 2 LASTPIN (-900 1700) $PN 209
J 2
(-910 1710);
DISPLAY 0.617021 (-910 1710);
PAINT ORANGE (-910 1710);
FORCEPROP 2 LASTPIN (-900 1650) $PN 212
J 2
(-910 1660);
DISPLAY 0.617021 (-910 1660);
PAINT ORANGE (-910 1660);
FORCEPROP 2 LASTPIN (-900 1600) $PN 215
J 2
(-910 1610);
DISPLAY 0.617021 (-910 1610);
PAINT ORANGE (-910 1610);
FORCEPROP 2 LASTPIN (-900 1550) $PN 217
J 2
(-910 1560);
DISPLAY 0.617021 (-910 1560);
PAINT ORANGE (-910 1560);
FORCEPROP 2 LASTPIN (-900 1500) $PN 220
J 2
(-910 1510);
DISPLAY 0.617021 (-910 1510);
PAINT ORANGE (-910 1510);
FORCEPROP 2 LASTPIN (-900 1450) $PN 223
J 2
(-910 1460);
DISPLAY 0.617021 (-910 1460);
PAINT ORANGE (-910 1460);
FORCEPROP 2 LASTPIN (-900 1400) $PN 226
J 2
(-910 1410);
DISPLAY 0.617021 (-910 1410);
PAINT ORANGE (-910 1410);
FORCEPROP 2 LASTPIN (-900 1350) $PN 229
J 2
(-910 1360);
DISPLAY 0.617021 (-910 1360);
PAINT ORANGE (-910 1360);
FORCEPROP 2 LASTPIN (-900 1300) $PN 231
J 2
(-910 1310);
DISPLAY 0.617021 (-910 1310);
PAINT ORANGE (-910 1310);
FORCEPROP 2 LASTPIN (-900 1250) $PN 233
J 2
(-910 1260);
DISPLAY 0.617021 (-910 1260);
PAINT ORANGE (-910 1260);
FORCEPROP 2 LASTPIN (-900 1200) $PN 236
J 2
(-910 1210);
DISPLAY 0.617021 (-910 1210);
PAINT ORANGE (-910 1210);
FORCEPROP 2 LASTPIN (100 2900) $PN 1
J 0
(110 2910);
DISPLAY 0.617021 (110 2910);
PAINT ORANGE (110 2910);
FORCEPROP 2 LASTPIN (100 2850) $PN 145
J 0
(110 2860);
DISPLAY 0.617021 (110 2860);
PAINT ORANGE (110 2860);
FORCEPROP 1 LAST PACK_TYPE PIP
J 0
(-850 3200);
PAINT SKYBLUE (-850 3200);
DISPLAY INVISIBLE (-850 3200);
FORCEPROP 2 LAST BOM_COST MEM
J 0
(-400 2050);
PAINT ORANGE (-400 2050);
DISPLAY INVISIBLE (-400 2050);
FORCEPROP 2 LAST CDS_LIB mstr_sconn
J 0
(-400 2050);
PAINT ORANGE (-400 2050);
DISPLAY INVISIBLE (-400 2050);
FORCEPROP 2 LAST SEC_TYPE PIP
J 0
(-850 3200);
DISPLAY 1.021277 (-850 3200);
PAINT ORANGE (-850 3200);
DISPLAY INVISIBLE (-850 3200);
FORCEPROP 2 LAST SEC 4
J 0
(-850 3200);
DISPLAY 0.680851 (-850 3200);
PAINT MONO (-850 3200);
DISPLAY INVISIBLE (-850 3200);
FORCEPROP 2 LAST CDS_LOCATION J1A1
J 0
(-850 3150);
DISPLAY 0.617021 (-850 3150);
PAINT AQUA (-850 3150);
DISPLAY INVISIBLE (-850 3150);
FORCEPROP 1 LAST PATH I169
J 0
(-400 3100);
PAINT GREEN (-400 3100);
DISPLAY INVISIBLE (-400 3100);
FORCEPROP 2 LAST ROOM DDR4_CH_M
J 0
(-400 2050);
PAINT ORANGE (-400 2050);
DISPLAY INVISIBLE (-400 2050);
FORCEADD TAP..6
R 2
(900 4000);
FORCEPROP 3 LASTPIN (850 4000) SIG_NAME M_M_DQS_DN<6>
J 0
(860 4010);
DISPLAY 0.659574 (860 4010);
PAINT MONO (860 4010);
DISPLAY INVISIBLE (860 4010);
FORCEPROP 1 LASTPIN (850 4000) BN 6
J 2
(900 4010);
DISPLAY 0.617021 (900 4010);
PAINT PINK (900 4010);
FORCEPROP 2 LAST CDS_LIB mstr_standard
J 0
(900 4000);
DISPLAY 0.787234 (900 4000);
PAINT MONO (900 4000);
DISPLAY INVISIBLE (900 4000);
FORCEPROP 1 LAST BODY_TYPE PLUMBING
J 2
(900 3950);
DISPLAY 1.234043 (900 3950);
PAINT GREEN (900 3950);
DISPLAY INVISIBLE (900 3950);
FORCEPROP 1 LAST HDL_TAP TRUE
J 2
(575 3875);
DISPLAY 1.234043 (575 3875);
PAINT GREEN (575 3875);
DISPLAY INVISIBLE (575 3875);
FORCEPROP 1 LAST PATH I17
J 2
(900 4000);
DISPLAY 0.936170 (900 4000);
PAINT GREEN (900 4000);
DISPLAY INVISIBLE (900 4000);
FORCEADD GND..1
R 2
(2500 1150);
FORCEPROP 3 LASTPIN (2500 1200) SIG_NAME GND\g
J 0
(2510 1210);
DISPLAY 0.659574 (2510 1210);
PAINT MONO (2510 1210);
DISPLAY INVISIBLE (2510 1210);
FORCEPROP 1 LAST VOLTAGE 0
J 0
(2500 1150);
PAINT SKYBLUE (2500 1150);
DISPLAY INVISIBLE (2500 1150);
FORCEPROP 2 LAST BOM_COST MEM
J 0
(2500 1155);
PAINT ORANGE (2500 1155);
DISPLAY INVISIBLE (2500 1155);
FORCEPROP 2 LAST CDS_LIB mstr_symbols
J 0
(2500 1150);
DISPLAY 0.787234 (2500 1150);
PAINT MONO (2500 1150);
DISPLAY INVISIBLE (2500 1150);
FORCEPROP 1 LAST SIZE 1B
J 2
(2425 1100);
DISPLAY 1.170213 (2425 1100);
PAINT GREEN (2425 1100);
DISPLAY INVISIBLE (2425 1100);
FORCEPROP 1 LAST BODY_TYPE PLUMBING
J 2
(2545 1107);
DISPLAY 0.340426 (2545 1107);
PAINT GREEN (2545 1107);
DISPLAY INVISIBLE (2545 1107);
FORCEPROP 1 LAST PATH I170
J 2
(2425 1150);
DISPLAY 1.404255 (2425 1150);
PAINT GREEN (2425 1150);
DISPLAY INVISIBLE (2425 1150);
FORCEPROP 2 LAST ROOM DDR4_CH_D
J 0
(2500 1155);
PAINT ORANGE (2500 1155);
DISPLAY INVISIBLE (2500 1155);
FORCEPROP 1 LAST HDL_POWER GND
J 2
(2500 1300);
DISPLAY 0.553191 (2500 1300);
PAINT GREEN (2500 1300);
DISPLAY INVISIBLE (2500 1300);
FORCEADD OFFPAGE..5
(-4225 2600);
FORCEPROP 2 LAST $XR23 94 
J 0
(-4719 2636);
DISPLAY 0.638298 (-4719 2636);
PAINT MONO (-4719 2636);
FORCEPROP 2 LAST $XR22 88 
J 0
(-4629 2636);
DISPLAY 0.638298 (-4629 2636);
PAINT MONO (-4629 2636);
FORCEPROP 2 LAST $XR21 86 
J 0
(-4539 2636);
DISPLAY 0.638298 (-4539 2636);
PAINT MONO (-4539 2636);
FORCEPROP 2 LAST $XR20 85 
J 0
(-4449 2636);
DISPLAY 0.638298 (-4449 2636);
PAINT MONO (-4449 2636);
FORCEPROP 2 LAST $XR19 84 
J 0
(-5259 2564);
DISPLAY 0.638298 (-5259 2564);
PAINT MONO (-5259 2564);
FORCEPROP 2 LAST $XR18 83 
J 0
(-5169 2564);
DISPLAY 0.638298 (-5169 2564);
PAINT MONO (-5169 2564);
FORCEPROP 2 LAST $XR17 82 
J 0
(-5079 2564);
DISPLAY 0.638298 (-5079 2564);
PAINT MONO (-5079 2564);
FORCEPROP 2 LAST $XR16 81 
J 0
(-4989 2564);
DISPLAY 0.638298 (-4989 2564);
PAINT MONO (-4989 2564);
FORCEPROP 2 LAST $XR15 80 
J 0
(-4899 2564);
DISPLAY 0.638298 (-4899 2564);
PAINT MONO (-4899 2564);
FORCEPROP 2 LAST $XR14 79 
J 0
(-4809 2564);
DISPLAY 0.638298 (-4809 2564);
PAINT MONO (-4809 2564);
FORCEPROP 2 LAST $XR13 78 
J 0
(-4719 2564);
DISPLAY 0.638298 (-4719 2564);
PAINT MONO (-4719 2564);
FORCEPROP 2 LAST $XR12 77 
J 0
(-4629 2564);
DISPLAY 0.638298 (-4629 2564);
PAINT MONO (-4629 2564);
FORCEPROP 2 LAST $XR11 54 
J 0
(-4539 2564);
DISPLAY 0.638298 (-4539 2564);
PAINT MONO (-4539 2564);
FORCEPROP 2 LAST $XR10 53 
J 0
(-4449 2564);
DISPLAY 0.638298 (-4449 2564);
PAINT MONO (-4449 2564);
FORCEPROP 2 LAST $XR9 52 
J 0
(-5259 2600);
DISPLAY 0.638298 (-5259 2600);
PAINT MONO (-5259 2600);
FORCEPROP 2 LAST $XR8 51 
J 0
(-5169 2600);
DISPLAY 0.638298 (-5169 2600);
PAINT MONO (-5169 2600);
FORCEPROP 2 LAST $XR7 50 
J 0
(-5079 2600);
DISPLAY 0.638298 (-5079 2600);
PAINT MONO (-5079 2600);
FORCEPROP 2 LAST $XR6 49 
J 0
(-4989 2600);
DISPLAY 0.638298 (-4989 2600);
PAINT MONO (-4989 2600);
FORCEPROP 2 LAST $XR5 48 
J 0
(-4899 2600);
DISPLAY 0.638298 (-4899 2600);
PAINT MONO (-4899 2600);
FORCEPROP 2 LAST $XR4 47 
J 0
(-4809 2600);
DISPLAY 0.638298 (-4809 2600);
PAINT MONO (-4809 2600);
FORCEPROP 2 LAST $XR3 46 
J 0
(-4719 2600);
DISPLAY 0.638298 (-4719 2600);
PAINT MONO (-4719 2600);
FORCEPROP 2 LAST $XR2 45 
J 0
(-4629 2600);
DISPLAY 0.638298 (-4629 2600);
PAINT MONO (-4629 2600);
FORCEPROP 2 LAST $XR1 44 
J 0
(-4539 2600);
DISPLAY 0.638298 (-4539 2600);
PAINT MONO (-4539 2600);
FORCEPROP 2 LAST $XR0 43 
J 0
(-4449 2600);
DISPLAY 0.638298 (-4449 2600);
PAINT MONO (-4449 2600);
FORCEPROP 2 LAST CDS_LIB mstr_standard
J 0
(-4225 2600);
DISPLAY 0.787234 (-4225 2600);
PAINT MONO (-4225 2600);
DISPLAY INVISIBLE (-4225 2600);
FORCEPROP 1 LAST OFFPAGE TRUE
J 0
(-3900 2475);
DISPLAY 1.404255 (-3900 2475);
PAINT GREEN (-3900 2475);
DISPLAY INVISIBLE (-3900 2475);
FORCEPROP 1 LAST COMMENT_BODY TRUE
J 0
(-4125 2525);
DISPLAY 1.404255 (-4125 2525);
PAINT GREEN (-4125 2525);
DISPLAY INVISIBLE (-4125 2525);
FORCEPROP 2 LAST PATH I171
J 0
(-4175 2675);
DISPLAY 0.787234 (-4175 2675);
PAINT ORANGE (-4175 2675);
DISPLAY INVISIBLE (-4175 2675);
FORCEADD OFFPAGE..6
(-3850 1900);
FORCEPROP 2 LASTPIN (-3800 1900) SIG_NAME SMB_DDR_KLM_VPP_SDA
J 0
(-3760 1910);
DISPLAY 0.617021 (-3760 1910);
PAINT ORANGE (-3760 1910);
FORCEPROP 2 LAST $XR5 99 
J 0
(-4549 1900);
DISPLAY 0.638298 (-4549 1900);
PAINT MONO (-4549 1900);
FORCEPROP 2 LAST $XR4 88 
J 0
(-4459 1900);
DISPLAY 0.638298 (-4459 1900);
PAINT MONO (-4459 1900);
FORCEPROP 2 LAST $XR3 86 
J 0
(-4369 1900);
DISPLAY 0.638298 (-4369 1900);
PAINT MONO (-4369 1900);
FORCEPROP 2 LAST $XR2 85 
J 0
(-4279 1900);
DISPLAY 0.638298 (-4279 1900);
PAINT MONO (-4279 1900);
FORCEPROP 2 LAST $XR1 84 
J 0
(-4189 1900);
DISPLAY 0.638298 (-4189 1900);
PAINT MONO (-4189 1900);
FORCEPROP 2 LAST $XR0 83 
J 0
(-4099 1900);
DISPLAY 0.638298 (-4099 1900);
PAINT MONO (-4099 1900);
FORCEPROP 2 LAST CDS_LIB mstr_standard
J 0
(-3850 1900);
DISPLAY 0.787234 (-3850 1900);
PAINT MONO (-3850 1900);
DISPLAY INVISIBLE (-3850 1900);
FORCEPROP 1 LAST OFFPAGE TRUE
J 0
(-3525 1775);
DISPLAY 0.936170 (-3525 1775);
PAINT GREEN (-3525 1775);
DISPLAY INVISIBLE (-3525 1775);
FORCEPROP 1 LAST COMMENT_BODY TRUE
J 0
(-3750 1825);
DISPLAY 0.936170 (-3750 1825);
PAINT GREEN (-3750 1825);
DISPLAY INVISIBLE (-3750 1825);
FORCEPROP 2 LAST PATH I172
J 0
(-4150 1950);
DISPLAY 0.787234 (-4150 1950);
PAINT ORANGE (-4150 1950);
DISPLAY INVISIBLE (-4150 1950);
FORCEADD OFFPAGE..1
(-4800 1750);
FORCEPROP 2 LAST $XR1 88 
J 0
(-5172 1750);
DISPLAY 0.638298 (-5172 1750);
PAINT MONO (-5172 1750);
FORCEPROP 2 LAST $XR0 100 
J 0
(-5082 1750);
DISPLAY 0.638298 (-5082 1750);
PAINT MONO (-5082 1750);
FORCEPROP 2 LAST CDS_LIB mstr_standard
J 0
(-4800 1750);
DISPLAY 0.787234 (-4800 1750);
PAINT MONO (-4800 1750);
DISPLAY INVISIBLE (-4800 1750);
FORCEPROP 1 LAST OFFPAGE TRUE
J 0
(-4475 1625);
DISPLAY 0.936170 (-4475 1625);
PAINT GREEN (-4475 1625);
DISPLAY INVISIBLE (-4475 1625);
FORCEPROP 1 LAST COMMENT_BODY TRUE
J 0
(-4675 1650);
DISPLAY 0.936170 (-4675 1650);
PAINT GREEN (-4675 1650);
DISPLAY INVISIBLE (-4675 1650);
FORCEPROP 2 LAST PATH I173
J 0
(-5050 1800);
DISPLAY 0.787234 (-5050 1800);
PAINT ORANGE (-5050 1800);
DISPLAY INVISIBLE (-5050 1800);
FORCEADD OFFPAGE..1
(-3850 1850);
FORCEPROP 2 LAST $XR5 88 
J 0
(-4551 1850);
DISPLAY 0.638298 (-4551 1850);
PAINT MONO (-4551 1850);
FORCEPROP 2 LAST $XR4 86 
J 0
(-4461 1850);
DISPLAY 0.638298 (-4461 1850);
PAINT MONO (-4461 1850);
FORCEPROP 2 LAST $XR3 85 
J 0
(-4371 1850);
DISPLAY 0.638298 (-4371 1850);
PAINT MONO (-4371 1850);
FORCEPROP 2 LAST $XR2 84 
J 0
(-4281 1850);
DISPLAY 0.638298 (-4281 1850);
PAINT MONO (-4281 1850);
FORCEPROP 2 LAST $XR1 83 
J 0
(-4191 1850);
DISPLAY 0.638298 (-4191 1850);
PAINT MONO (-4191 1850);
FORCEPROP 2 LAST $XR0 99 
J 0
(-4101 1850);
DISPLAY 0.638298 (-4101 1850);
PAINT MONO (-4101 1850);
FORCEPROP 2 LAST CDS_LIB mstr_standard
J 0
(-3850 1850);
DISPLAY 0.787234 (-3850 1850);
PAINT MONO (-3850 1850);
DISPLAY INVISIBLE (-3850 1850);
FORCEPROP 1 LAST OFFPAGE TRUE
J 0
(-3525 1725);
DISPLAY 0.936170 (-3525 1725);
PAINT GREEN (-3525 1725);
DISPLAY INVISIBLE (-3525 1725);
FORCEPROP 1 LAST COMMENT_BODY TRUE
J 0
(-3725 1750);
DISPLAY 0.936170 (-3725 1750);
PAINT GREEN (-3725 1750);
DISPLAY INVISIBLE (-3725 1750);
FORCEPROP 2 LAST PATH I174
J 0
(-4125 1900);
DISPLAY 0.787234 (-4125 1900);
PAINT ORANGE (-4125 1900);
DISPLAY INVISIBLE (-4125 1900);
FORCEADD GND..1
R 2
(-5000 1850);
FORCEPROP 3 LASTPIN (-5000 1900) SIG_NAME GND\g
J 0
(-4990 1910);
DISPLAY 0.659574 (-4990 1910);
PAINT MONO (-4990 1910);
DISPLAY INVISIBLE (-4990 1910);
FORCEPROP 1 LAST VOLTAGE 0
J 0
(-5000 1850);
PAINT SKYBLUE (-5000 1850);
DISPLAY INVISIBLE (-5000 1850);
FORCEPROP 2 LAST BOM_COST MEM
J 0
(-5000 1855);
PAINT ORANGE (-5000 1855);
DISPLAY INVISIBLE (-5000 1855);
FORCEPROP 2 LAST CDS_LIB mstr_symbols
J 0
(-5000 1850);
DISPLAY 0.787234 (-5000 1850);
PAINT MONO (-5000 1850);
DISPLAY INVISIBLE (-5000 1850);
FORCEPROP 1 LAST SIZE 1B
J 2
(-5075 1800);
DISPLAY 1.170213 (-5075 1800);
PAINT GREEN (-5075 1800);
DISPLAY INVISIBLE (-5075 1800);
FORCEPROP 1 LAST BODY_TYPE PLUMBING
J 2
(-4955 1807);
DISPLAY 0.340426 (-4955 1807);
PAINT GREEN (-4955 1807);
DISPLAY INVISIBLE (-4955 1807);
FORCEPROP 1 LAST PATH I176
J 2
(-5075 1850);
DISPLAY 1.404255 (-5075 1850);
PAINT GREEN (-5075 1850);
DISPLAY INVISIBLE (-5075 1850);
FORCEPROP 2 LAST ROOM DDR4_CH_D
J 0
(-5000 1855);
PAINT ORANGE (-5000 1855);
DISPLAY INVISIBLE (-5000 1855);
FORCEPROP 1 LAST HDL_POWER GND
J 2
(-5000 2000);
DISPLAY 0.553191 (-5000 2000);
PAINT GREEN (-5000 2000);
DISPLAY INVISIBLE (-5000 2000);
FORCEADD GND..1
(-4650 1300);
FORCEPROP 3 LASTPIN (-4650 1350) SIG_NAME GND\g
J 0
(-4640 1360);
DISPLAY 0.659574 (-4640 1360);
PAINT MONO (-4640 1360);
DISPLAY INVISIBLE (-4640 1360);
FORCEPROP 1 LAST VOLTAGE 16V
J 0
(-4650 1300);
PAINT SKYBLUE (-4650 1300);
DISPLAY INVISIBLE (-4650 1300);
FORCEPROP 2 LAST CDS_LIB mstr_symbols
J 0
(-4650 1300);
PAINT ORANGE (-4650 1300);
DISPLAY INVISIBLE (-4650 1300);
FORCEPROP 2 LAST BOM_COST MEM
J 0
(-4650 1305);
PAINT ORANGE (-4650 1305);
DISPLAY INVISIBLE (-4650 1305);
FORCEPROP 1 LAST SIZE 1B
J 0
(-4575 1250);
DISPLAY 1.787234 (-4575 1250);
PAINT GREEN (-4575 1250);
DISPLAY INVISIBLE (-4575 1250);
FORCEPROP 1 LAST BODY_TYPE PLUMBING
J 0
(-4695 1257);
DISPLAY 0.340426 (-4695 1257);
PAINT GREEN (-4695 1257);
DISPLAY INVISIBLE (-4695 1257);
FORCEPROP 1 LAST PATH I177
J 0
(-4575 1300);
DISPLAY 1.404255 (-4575 1300);
PAINT GREEN (-4575 1300);
DISPLAY INVISIBLE (-4575 1300);
FORCEPROP 2 LAST ROOM DDR4_CH_M1
J 0
(-4650 1305);
PAINT ORANGE (-4650 1305);
DISPLAY INVISIBLE (-4650 1305);
FORCEPROP 1 LAST HDL_POWER GND
J 0
(-4650 1450);
DISPLAY 1.404255 (-4650 1450);
PAINT GREEN (-4650 1450);
DISPLAY INVISIBLE (-4650 1450);
FORCEADD CAP_A..1
R 2
(-4650 1550);
FORCEPROP 1 LAST LOCATION C1A5
J 2
(-4700 1650);
DISPLAY 0.617021 (-4700 1650);
PAINT AQUA (-4700 1650);
FORCEPROP 1 LAST PART_NUMBER A36096-045
J 2
(-4700 1400);
DISPLAY 0.617021 (-4700 1400);
PAINT BLUE (-4700 1400);
FORCEPROP 1 LAST VALUE 0.01UF
J 2
(-4700 1600);
DISPLAY 0.617021 (-4700 1600);
PAINT SKYBLUE (-4700 1600);
FORCEPROP 1 LAST TOLERANCE 10%
J 2
(-4700 1500);
DISPLAY 0.617021 (-4700 1500);
PAINT SKYBLUE (-4700 1500);
FORCEPROP 1 LAST PACK_TYPE 0402V
J 2
(-4700 1350);
DISPLAY 0.617021 (-4700 1350);
PAINT SKYBLUE (-4700 1350);
FORCEPROP 1 LAST VOLTAGE 25V
J 2
(-4700 1550);
DISPLAY 0.617021 (-4700 1550);
PAINT SKYBLUE (-4700 1550);
FORCEPROP 1 LAST MATERIAL X7R
J 2
(-4700 1450);
DISPLAY 0.617021 (-4700 1450);
PAINT SKYBLUE (-4700 1450);
FORCEPROP 1 LASTPIN (-4650 1650) $PN 1
J 2
(-4660 1630);
DISPLAY 0.617021 (-4660 1630);
PAINT ORANGE (-4660 1630);
FORCEPROP 1 LASTPIN (-4650 1450) $PN 2
J 2
(-4660 1430);
DISPLAY 0.617021 (-4660 1430);
PAINT ORANGE (-4660 1430);
FORCEPROP 2 LAST CDS_LOCATION C1A5
J 2
(-4700 1650);
DISPLAY 0.617021 (-4700 1650);
PAINT AQUA (-4700 1650);
DISPLAY INVISIBLE (-4700 1650);
FORCEPROP 2 LAST BOM_COST MEM
J 0
(-4650 1550);
PAINT ORANGE (-4650 1550);
DISPLAY INVISIBLE (-4650 1550);
FORCEPROP 2 LAST CDS_LIB dev_discrete
J 0
(-4650 1550);
PAINT ORANGE (-4650 1550);
DISPLAY INVISIBLE (-4650 1550);
FORCEPROP 2 LAST CDS_SEC 1
J 0
(-4700 1700);
PAINT ORANGE (-4700 1700);
DISPLAY INVISIBLE (-4700 1700);
FORCEPROP 2 LAST SEC_TYPE 0402V
J 0
(-4700 1750);
DISPLAY 1.021277 (-4700 1750);
PAINT ORANGE (-4700 1750);
DISPLAY INVISIBLE (-4700 1750);
FORCEPROP 2 LAST SEC 1
J 0
(-4700 1750);
PAINT MONO (-4700 1750);
DISPLAY INVISIBLE (-4700 1750);
FORCEPROP 1 LAST PATH I178
J 2
(-4700 1700);
DISPLAY 0.978723 (-4700 1700);
PAINT WHITE (-4700 1700);
DISPLAY INVISIBLE (-4700 1700);
FORCEPROP 2 LAST ROOM DDR4_CH_M
J 0
(-4650 1550);
PAINT ORANGE (-4650 1550);
DISPLAY INVISIBLE (-4650 1550);
FORCEADD PVPP_KLM..1
(-1100 3050);
FORCEPROP 3 LASTPIN (-1100 3000) SIG_NAME PVPP_KLM\g
J 0
(-1090 3010);
DISPLAY 0.659574 (-1090 3010);
PAINT MONO (-1090 3010);
DISPLAY INVISIBLE (-1090 3010);
FORCEPROP 1 LAST VOLTAGE 2.5V
J 0
(-1145 3007);
DISPLAY 0.340426 (-1145 3007);
PAINT SKYBLUE (-1145 3007);
DISPLAY INVISIBLE (-1145 3007);
FORCEPROP 0 LAST BOM_COST MEM
J 0
(-1100 3150);
PAINT ORANGE (-1100 3150);
DISPLAY INVISIBLE (-1100 3150);
FORCEPROP 2 LAST CDS_LIB mstr_symbols
J 0
(-1100 3050);
PAINT ORANGE (-1100 3050);
DISPLAY INVISIBLE (-1100 3050);
FORCEPROP 1 LAST BODY_TYPE PLUMBING
J 0
(-1145 3007);
DISPLAY 0.340426 (-1145 3007);
PAINT GREEN (-1145 3007);
DISPLAY INVISIBLE (-1145 3007);
FORCEPROP 1 LAST PATH I179
J 0
(-1050 3075);
DISPLAY 0.872340 (-1050 3075);
PAINT AQUA (-1050 3075);
DISPLAY INVISIBLE (-1050 3075);
FORCEPROP 2 LAST ROOM DDR4_CH_D
J 0
(-1100 3150);
PAINT ORANGE (-1100 3150);
DISPLAY INVISIBLE (-1100 3150);
FORCEPROP 1 LAST HDL_POWER PVPP_KLM
J 1
(-1100 3100);
DISPLAY 0.872340 (-1100 3100);
PAINT GREEN (-1100 3100);
DISPLAY INVISIBLE (-1100 3100);
FORCEADD TAP..6
R 2
(900 3900);
FORCEPROP 3 LASTPIN (850 3900) SIG_NAME M_M_DQS_DN<5>
J 0
(860 3910);
DISPLAY 0.659574 (860 3910);
PAINT MONO (860 3910);
DISPLAY INVISIBLE (860 3910);
FORCEPROP 1 LASTPIN (850 3900) BN 5
J 2
(900 3910);
DISPLAY 0.617021 (900 3910);
PAINT PINK (900 3910);
FORCEPROP 2 LAST CDS_LIB mstr_standard
J 0
(900 3900);
DISPLAY 0.787234 (900 3900);
PAINT MONO (900 3900);
DISPLAY INVISIBLE (900 3900);
FORCEPROP 1 LAST BODY_TYPE PLUMBING
J 2
(900 3850);
DISPLAY 1.234043 (900 3850);
PAINT GREEN (900 3850);
DISPLAY INVISIBLE (900 3850);
FORCEPROP 1 LAST HDL_TAP TRUE
J 2
(575 3775);
DISPLAY 1.234043 (575 3775);
PAINT GREEN (575 3775);
DISPLAY INVISIBLE (575 3775);
FORCEPROP 1 LAST PATH I18
J 2
(900 3900);
DISPLAY 0.936170 (900 3900);
PAINT GREEN (900 3900);
DISPLAY INVISIBLE (900 3900);
FORCEADD PVPP_KLM..1
(-5000 2250);
FORCEPROP 3 LASTPIN (-5000 2200) SIG_NAME PVPP_KLM\g
J 0
(-4990 2210);
DISPLAY 0.659574 (-4990 2210);
PAINT MONO (-4990 2210);
DISPLAY INVISIBLE (-4990 2210);
FORCEPROP 1 LAST VOLTAGE 2.5V
J 0
(-5045 2207);
DISPLAY 0.340426 (-5045 2207);
PAINT SKYBLUE (-5045 2207);
DISPLAY INVISIBLE (-5045 2207);
FORCEPROP 0 LAST BOM_COST MEM
J 0
(-5000 2350);
PAINT ORANGE (-5000 2350);
DISPLAY INVISIBLE (-5000 2350);
FORCEPROP 2 LAST CDS_LIB mstr_symbols
J 0
(-5000 2250);
PAINT ORANGE (-5000 2250);
DISPLAY INVISIBLE (-5000 2250);
FORCEPROP 1 LAST BODY_TYPE PLUMBING
J 0
(-5045 2207);
DISPLAY 0.340426 (-5045 2207);
PAINT GREEN (-5045 2207);
DISPLAY INVISIBLE (-5045 2207);
FORCEPROP 1 LAST PATH I180
J 0
(-4950 2275);
DISPLAY 0.872340 (-4950 2275);
PAINT AQUA (-4950 2275);
DISPLAY INVISIBLE (-4950 2275);
FORCEPROP 2 LAST ROOM DDR4_CH_D
J 0
(-5000 2350);
PAINT ORANGE (-5000 2350);
DISPLAY INVISIBLE (-5000 2350);
FORCEPROP 1 LAST HDL_POWER PVPP_KLM
J 1
(-5000 2300);
DISPLAY 0.872340 (-5000 2300);
PAINT GREEN (-5000 2300);
DISPLAY INVISIBLE (-5000 2300);
FORCEADD OFFPAGE..1
(-3900 1450);
FORCEPROP 2 LAST $XR5 88 
J 0
(-4571 1450);
DISPLAY 0.638298 (-4571 1450);
PAINT MONO (-4571 1450);
FORCEPROP 2 LAST $XR4 86 
J 0
(-4481 1450);
DISPLAY 0.638298 (-4481 1450);
PAINT MONO (-4481 1450);
FORCEPROP 2 LAST $XR3 85 
J 0
(-4391 1450);
DISPLAY 0.638298 (-4391 1450);
PAINT MONO (-4391 1450);
FORCEPROP 2 LAST $XR2 84 
J 0
(-4301 1450);
DISPLAY 0.638298 (-4301 1450);
PAINT MONO (-4301 1450);
FORCEPROP 2 LAST $XR1 83 
J 0
(-4211 1450);
DISPLAY 0.638298 (-4211 1450);
PAINT MONO (-4211 1450);
FORCEPROP 2 LAST $XR0 89 
J 0
(-4121 1450);
DISPLAY 0.638298 (-4121 1450);
PAINT MONO (-4121 1450);
FORCEPROP 2 LAST CDS_LIB mstr_standard
J 0
(-3900 1450);
PAINT ORANGE (-3900 1450);
DISPLAY INVISIBLE (-3900 1450);
FORCEPROP 1 LAST OFFPAGE TRUE
J 0
(-3575 1325);
DISPLAY 0.936170 (-3575 1325);
PAINT GREEN (-3575 1325);
DISPLAY INVISIBLE (-3575 1325);
FORCEPROP 1 LAST COMMENT_BODY TRUE
J 0
(-3775 1350);
DISPLAY 0.936170 (-3775 1350);
PAINT GREEN (-3775 1350);
DISPLAY INVISIBLE (-3775 1350);
FORCEPROP 2 LAST PATH I181
J 0
(-3850 1525);
PAINT ORANGE (-3850 1525);
DISPLAY INVISIBLE (-3850 1525);
FORCEADD SCONN288_H44441004..3
(1800 2450);
FORCEPROP 1 LAST PART_NUMBER H44441-004
J 0
(1350 1100);
DISPLAY 0.617021 (1350 1100);
PAINT BLUE (1350 1100);
FORCEPROP 1 LAST MATERIAL SCONN
J 0
(1350 3800);
DISPLAY 0.617021 (1350 3800);
PAINT SKYBLUE (1350 3800);
FORCEPROP 2 LASTPIN (1300 3600) $PN 2
J 2
(1290 3610);
DISPLAY 0.617021 (1290 3610);
PAINT ORANGE (1290 3610);
FORCEPROP 2 LASTPIN (1300 3550) $PN 4
J 2
(1290 3560);
DISPLAY 0.617021 (1290 3560);
PAINT ORANGE (1290 3560);
FORCEPROP 2 LASTPIN (1300 3500) $PN 6
J 2
(1290 3510);
DISPLAY 0.617021 (1290 3510);
PAINT ORANGE (1290 3510);
FORCEPROP 2 LASTPIN (1300 3450) $PN 9
J 2
(1290 3460);
DISPLAY 0.617021 (1290 3460);
PAINT ORANGE (1290 3460);
FORCEPROP 2 LASTPIN (1300 3400) $PN 11
J 2
(1290 3410);
DISPLAY 0.617021 (1290 3410);
PAINT ORANGE (1290 3410);
FORCEPROP 2 LASTPIN (1300 3350) $PN 13
J 2
(1290 3360);
DISPLAY 0.617021 (1290 3360);
PAINT ORANGE (1290 3360);
FORCEPROP 2 LASTPIN (1300 3300) $PN 15
J 2
(1290 3310);
DISPLAY 0.617021 (1290 3310);
PAINT ORANGE (1290 3310);
FORCEPROP 2 LASTPIN (1300 3250) $PN 17
J 2
(1290 3260);
DISPLAY 0.617021 (1290 3260);
PAINT ORANGE (1290 3260);
FORCEPROP 2 LASTPIN (1300 3200) $PN 20
J 2
(1290 3210);
DISPLAY 0.617021 (1290 3210);
PAINT ORANGE (1290 3210);
FORCEPROP 2 LASTPIN (1300 3150) $PN 22
J 2
(1290 3160);
DISPLAY 0.617021 (1290 3160);
PAINT ORANGE (1290 3160);
FORCEPROP 2 LASTPIN (1300 3100) $PN 24
J 2
(1290 3110);
DISPLAY 0.617021 (1290 3110);
PAINT ORANGE (1290 3110);
FORCEPROP 2 LASTPIN (1300 3050) $PN 26
J 2
(1290 3060);
DISPLAY 0.617021 (1290 3060);
PAINT ORANGE (1290 3060);
FORCEPROP 2 LASTPIN (1300 3000) $PN 28
J 2
(1290 3010);
DISPLAY 0.617021 (1290 3010);
PAINT ORANGE (1290 3010);
FORCEPROP 2 LASTPIN (1300 2950) $PN 31
J 2
(1290 2960);
DISPLAY 0.617021 (1290 2960);
PAINT ORANGE (1290 2960);
FORCEPROP 2 LASTPIN (1300 2900) $PN 33
J 2
(1290 2910);
DISPLAY 0.617021 (1290 2910);
PAINT ORANGE (1290 2910);
FORCEPROP 2 LASTPIN (1300 2850) $PN 35
J 2
(1290 2860);
DISPLAY 0.617021 (1290 2860);
PAINT ORANGE (1290 2860);
FORCEPROP 2 LASTPIN (1300 2800) $PN 37
J 2
(1290 2810);
DISPLAY 0.617021 (1290 2810);
PAINT ORANGE (1290 2810);
FORCEPROP 2 LASTPIN (1300 2750) $PN 39
J 2
(1290 2760);
DISPLAY 0.617021 (1290 2760);
PAINT ORANGE (1290 2760);
FORCEPROP 2 LASTPIN (1300 2700) $PN 42
J 2
(1290 2710);
DISPLAY 0.617021 (1290 2710);
PAINT ORANGE (1290 2710);
FORCEPROP 2 LASTPIN (1300 2650) $PN 44
J 2
(1290 2660);
DISPLAY 0.617021 (1290 2660);
PAINT ORANGE (1290 2660);
FORCEPROP 2 LASTPIN (1300 2600) $PN 46
J 2
(1290 2610);
DISPLAY 0.617021 (1290 2610);
PAINT ORANGE (1290 2610);
FORCEPROP 2 LASTPIN (1300 2550) $PN 48
J 2
(1290 2560);
DISPLAY 0.617021 (1290 2560);
PAINT ORANGE (1290 2560);
FORCEPROP 2 LASTPIN (1300 2500) $PN 50
J 2
(1290 2510);
DISPLAY 0.617021 (1290 2510);
PAINT ORANGE (1290 2510);
FORCEPROP 2 LASTPIN (1300 2450) $PN 53
J 2
(1290 2460);
DISPLAY 0.617021 (1290 2460);
PAINT ORANGE (1290 2460);
FORCEPROP 2 LASTPIN (1300 2400) $PN 55
J 2
(1290 2410);
DISPLAY 0.617021 (1290 2410);
PAINT ORANGE (1290 2410);
FORCEPROP 2 LASTPIN (1300 2350) $PN 57
J 2
(1290 2360);
DISPLAY 0.617021 (1290 2360);
PAINT ORANGE (1290 2360);
FORCEPROP 2 LASTPIN (1300 2300) $PN 94
J 2
(1290 2310);
DISPLAY 0.617021 (1290 2310);
PAINT ORANGE (1290 2310);
FORCEPROP 2 LASTPIN (1300 2250) $PN 96
J 2
(1290 2260);
DISPLAY 0.617021 (1290 2260);
PAINT ORANGE (1290 2260);
FORCEPROP 2 LASTPIN (1300 2200) $PN 98
J 2
(1290 2210);
DISPLAY 0.617021 (1290 2210);
PAINT ORANGE (1290 2210);
FORCEPROP 2 LASTPIN (1300 2150) $PN 101
J 2
(1290 2160);
DISPLAY 0.617021 (1290 2160);
PAINT ORANGE (1290 2160);
FORCEPROP 2 LASTPIN (1300 2100) $PN 103
J 2
(1290 2110);
DISPLAY 0.617021 (1290 2110);
PAINT ORANGE (1290 2110);
FORCEPROP 2 LASTPIN (1300 2050) $PN 105
J 2
(1290 2060);
DISPLAY 0.617021 (1290 2060);
PAINT ORANGE (1290 2060);
FORCEPROP 2 LASTPIN (1300 1900) $PN 112
J 2
(1290 1910);
DISPLAY 0.617021 (1290 1910);
PAINT ORANGE (1290 1910);
FORCEPROP 2 LASTPIN (1300 1850) $PN 114
J 2
(1290 1860);
DISPLAY 0.617021 (1290 1860);
PAINT ORANGE (1290 1860);
FORCEPROP 2 LASTPIN (1300 1800) $PN 116
J 2
(1290 1810);
DISPLAY 0.617021 (1290 1810);
PAINT ORANGE (1290 1810);
FORCEPROP 2 LASTPIN (1300 1750) $PN 118
J 2
(1290 1760);
DISPLAY 0.617021 (1290 1760);
PAINT ORANGE (1290 1760);
FORCEPROP 2 LASTPIN (1300 1700) $PN 120
J 2
(1290 1710);
DISPLAY 0.617021 (1290 1710);
PAINT ORANGE (1290 1710);
FORCEPROP 2 LASTPIN (1300 1650) $PN 123
J 2
(1290 1660);
DISPLAY 0.617021 (1290 1660);
PAINT ORANGE (1290 1660);
FORCEPROP 2 LASTPIN (1300 1600) $PN 125
J 2
(1290 1610);
DISPLAY 0.617021 (1290 1610);
PAINT ORANGE (1290 1610);
FORCEPROP 2 LASTPIN (1300 1550) $PN 127
J 2
(1290 1560);
DISPLAY 0.617021 (1290 1560);
PAINT ORANGE (1290 1560);
FORCEPROP 2 LASTPIN (1300 1450) $PN 131
J 2
(1290 1460);
DISPLAY 0.617021 (1290 1460);
PAINT ORANGE (1290 1460);
FORCEPROP 2 LASTPIN (1300 1400) $PN 134
J 2
(1290 1410);
DISPLAY 0.617021 (1290 1410);
PAINT ORANGE (1290 1410);
FORCEPROP 2 LASTPIN (1300 1350) $PN 136
J 2
(1290 1360);
DISPLAY 0.617021 (1290 1360);
PAINT ORANGE (1290 1360);
FORCEPROP 2 LASTPIN (1300 1300) $PN 138
J 2
(1290 1310);
DISPLAY 0.617021 (1290 1310);
PAINT ORANGE (1290 1310);
FORCEPROP 2 LASTPIN (2300 3600) $PN 147
J 0
(2310 3610);
DISPLAY 0.617021 (2310 3610);
PAINT ORANGE (2310 3610);
FORCEPROP 2 LASTPIN (2300 3550) $PN 149
J 0
(2310 3560);
DISPLAY 0.617021 (2310 3560);
PAINT ORANGE (2310 3560);
FORCEPROP 2 LASTPIN (2300 3500) $PN 151
J 0
(2310 3510);
DISPLAY 0.617021 (2310 3510);
PAINT ORANGE (2310 3510);
FORCEPROP 2 LASTPIN (2300 3450) $PN 154
J 0
(2310 3460);
DISPLAY 0.617021 (2310 3460);
PAINT ORANGE (2310 3460);
FORCEPROP 2 LASTPIN (2300 3400) $PN 156
J 0
(2310 3410);
DISPLAY 0.617021 (2310 3410);
PAINT ORANGE (2310 3410);
FORCEPROP 2 LASTPIN (2300 3350) $PN 158
J 0
(2310 3360);
DISPLAY 0.617021 (2310 3360);
PAINT ORANGE (2310 3360);
FORCEPROP 2 LASTPIN (2300 3300) $PN 160
J 0
(2310 3310);
DISPLAY 0.617021 (2310 3310);
PAINT ORANGE (2310 3310);
FORCEPROP 2 LASTPIN (2300 3250) $PN 162
J 0
(2310 3260);
DISPLAY 0.617021 (2310 3260);
PAINT ORANGE (2310 3260);
FORCEPROP 2 LASTPIN (2300 3200) $PN 165
J 0
(2310 3210);
DISPLAY 0.617021 (2310 3210);
PAINT ORANGE (2310 3210);
FORCEPROP 2 LASTPIN (2300 3150) $PN 167
J 0
(2310 3160);
DISPLAY 0.617021 (2310 3160);
PAINT ORANGE (2310 3160);
FORCEPROP 2 LASTPIN (2300 3100) $PN 169
J 0
(2310 3110);
DISPLAY 0.617021 (2310 3110);
PAINT ORANGE (2310 3110);
FORCEPROP 2 LASTPIN (2300 2950) $PN 176
J 0
(2310 2960);
DISPLAY 0.617021 (2310 2960);
PAINT ORANGE (2310 2960);
FORCEPROP 2 LASTPIN (2300 2900) $PN 178
J 0
(2310 2910);
DISPLAY 0.617021 (2310 2910);
PAINT ORANGE (2310 2910);
FORCEPROP 2 LASTPIN (2300 2850) $PN 180
J 0
(2310 2860);
DISPLAY 0.617021 (2310 2860);
PAINT ORANGE (2310 2860);
FORCEPROP 2 LASTPIN (2300 2800) $PN 182
J 0
(2310 2810);
DISPLAY 0.617021 (2310 2810);
PAINT ORANGE (2310 2810);
FORCEPROP 2 LASTPIN (2300 2750) $PN 184
J 0
(2310 2760);
DISPLAY 0.617021 (2310 2760);
PAINT ORANGE (2310 2760);
FORCEPROP 2 LASTPIN (2300 2700) $PN 187
J 0
(2310 2710);
DISPLAY 0.617021 (2310 2710);
PAINT ORANGE (2310 2710);
FORCEPROP 2 LASTPIN (2300 2650) $PN 189
J 0
(2310 2660);
DISPLAY 0.617021 (2310 2660);
PAINT ORANGE (2310 2660);
FORCEPROP 2 LASTPIN (2300 2600) $PN 191
J 0
(2310 2610);
DISPLAY 0.617021 (2310 2610);
PAINT ORANGE (2310 2610);
FORCEPROP 2 LASTPIN (2300 2550) $PN 193
J 0
(2310 2560);
DISPLAY 0.617021 (2310 2560);
PAINT ORANGE (2310 2560);
FORCEPROP 2 LASTPIN (2300 2500) $PN 195
J 0
(2310 2510);
DISPLAY 0.617021 (2310 2510);
PAINT ORANGE (2310 2510);
FORCEPROP 2 LASTPIN (2300 2450) $PN 198
J 0
(2310 2460);
DISPLAY 0.617021 (2310 2460);
PAINT ORANGE (2310 2460);
FORCEPROP 2 LASTPIN (2300 2400) $PN 200
J 0
(2310 2410);
DISPLAY 0.617021 (2310 2410);
PAINT ORANGE (2310 2410);
FORCEPROP 2 LASTPIN (2300 2350) $PN 202
J 0
(2310 2360);
DISPLAY 0.617021 (2310 2360);
PAINT ORANGE (2310 2360);
FORCEPROP 2 LASTPIN (2300 2300) $PN 239
J 0
(2310 2310);
DISPLAY 0.617021 (2310 2310);
PAINT ORANGE (2310 2310);
FORCEPROP 2 LASTPIN (2300 2250) $PN 241
J 0
(2310 2260);
DISPLAY 0.617021 (2310 2260);
PAINT ORANGE (2310 2260);
FORCEPROP 2 LASTPIN (2300 2200) $PN 243
J 0
(2310 2210);
DISPLAY 0.617021 (2310 2210);
PAINT ORANGE (2310 2210);
FORCEPROP 2 LASTPIN (2300 2150) $PN 246
J 0
(2310 2160);
DISPLAY 0.617021 (2310 2160);
PAINT ORANGE (2310 2160);
FORCEPROP 2 LASTPIN (2300 2100) $PN 248
J 0
(2310 2110);
DISPLAY 0.617021 (2310 2110);
PAINT ORANGE (2310 2110);
FORCEPROP 2 LASTPIN (2300 2050) $PN 250
J 0
(2310 2060);
DISPLAY 0.617021 (2310 2060);
PAINT ORANGE (2310 2060);
FORCEPROP 2 LASTPIN (2300 2000) $PN 252
J 0
(2310 2010);
DISPLAY 0.617021 (2310 2010);
PAINT ORANGE (2310 2010);
FORCEPROP 2 LASTPIN (2300 1950) $PN 254
J 0
(2310 1960);
DISPLAY 0.617021 (2310 1960);
PAINT ORANGE (2310 1960);
FORCEPROP 2 LASTPIN (2300 1900) $PN 257
J 0
(2310 1910);
DISPLAY 0.617021 (2310 1910);
PAINT ORANGE (2310 1910);
FORCEPROP 2 LASTPIN (2300 1850) $PN 259
J 0
(2310 1860);
DISPLAY 0.617021 (2310 1860);
PAINT ORANGE (2310 1860);
FORCEPROP 2 LASTPIN (2300 1800) $PN 261
J 0
(2310 1810);
DISPLAY 0.617021 (2310 1810);
PAINT ORANGE (2310 1810);
FORCEPROP 2 LASTPIN (2300 1750) $PN 263
J 0
(2310 1760);
DISPLAY 0.617021 (2310 1760);
PAINT ORANGE (2310 1760);
FORCEPROP 2 LASTPIN (2300 1700) $PN 265
J 0
(2310 1710);
DISPLAY 0.617021 (2310 1710);
PAINT ORANGE (2310 1710);
FORCEPROP 2 LASTPIN (2300 1650) $PN 268
J 0
(2310 1660);
DISPLAY 0.617021 (2310 1660);
PAINT ORANGE (2310 1660);
FORCEPROP 2 LASTPIN (2300 1600) $PN 270
J 0
(2310 1610);
DISPLAY 0.617021 (2310 1610);
PAINT ORANGE (2310 1610);
FORCEPROP 2 LASTPIN (2300 1550) $PN 272
J 0
(2310 1560);
DISPLAY 0.617021 (2310 1560);
PAINT ORANGE (2310 1560);
FORCEPROP 2 LASTPIN (2300 1500) $PN 274
J 0
(2310 1510);
DISPLAY 0.617021 (2310 1510);
PAINT ORANGE (2310 1510);
FORCEPROP 2 LASTPIN (2300 1450) $PN 276
J 0
(2310 1460);
DISPLAY 0.617021 (2310 1460);
PAINT ORANGE (2310 1460);
FORCEPROP 2 LASTPIN (2300 1400) $PN 279
J 0
(2310 1410);
DISPLAY 0.617021 (2310 1410);
PAINT ORANGE (2310 1410);
FORCEPROP 2 LASTPIN (2300 1350) $PN 281
J 0
(2310 1360);
DISPLAY 0.617021 (2310 1360);
PAINT ORANGE (2310 1360);
FORCEPROP 2 LASTPIN (2300 1300) $PN 283
J 0
(2310 1310);
DISPLAY 0.617021 (2310 1310);
PAINT ORANGE (2310 1310);
FORCEPROP 2 LASTPIN (2300 3000) $PN 173
J 0
(2310 3010);
DISPLAY 0.617021 (2310 3010);
PAINT ORANGE (2310 3010);
FORCEPROP 1 LAST LOCATION J1A1
J 0
(1350 3850);
DISPLAY 0.617021 (1350 3850);
PAINT AQUA (1350 3850);
FORCEPROP 2 LASTPIN (1300 1950) $PN 109
J 2
(1290 1960);
DISPLAY 0.617021 (1290 1960);
PAINT ORANGE (1290 1960);
FORCEPROP 2 LASTPIN (1300 2000) $PN 107
J 2
(1290 2010);
DISPLAY 0.617021 (1290 2010);
PAINT ORANGE (1290 2010);
FORCEPROP 2 LASTPIN (2300 3050) $PN 171
J 0
(2310 3060);
DISPLAY 0.617021 (2310 3060);
PAINT ORANGE (2310 3060);
FORCEPROP 2 LASTPIN (1300 1500) $PN 129
J 2
(1290 1510);
DISPLAY 0.617021 (1290 1510);
PAINT ORANGE (1290 1510);
FORCEPROP 1 LAST PACK_TYPE PIP
J 0
(1350 3900);
PAINT SKYBLUE (1350 3900);
DISPLAY INVISIBLE (1350 3900);
FORCEPROP 2 LAST BOM_COST MEM
J 0
(1800 2450);
PAINT ORANGE (1800 2450);
DISPLAY INVISIBLE (1800 2450);
FORCEPROP 2 LAST CDS_LIB mstr_sconn
J 0
(1800 2450);
PAINT ORANGE (1800 2450);
DISPLAY INVISIBLE (1800 2450);
FORCEPROP 2 LAST SEC_TYPE PIP
J 0
(1350 3900);
DISPLAY 1.021277 (1350 3900);
PAINT ORANGE (1350 3900);
DISPLAY INVISIBLE (1350 3900);
FORCEPROP 2 LAST SEC 3
J 0
(1350 3900);
DISPLAY 0.680851 (1350 3900);
PAINT MONO (1350 3900);
DISPLAY INVISIBLE (1350 3900);
FORCEPROP 2 LAST CDS_LOCATION J1A1
J 0
(1350 3850);
DISPLAY 0.617021 (1350 3850);
PAINT AQUA (1350 3850);
DISPLAY INVISIBLE (1350 3850);
FORCEPROP 1 LAST PATH I185
J 0
(1800 3800);
PAINT GREEN (1800 3800);
DISPLAY INVISIBLE (1800 3800);
FORCEPROP 2 LAST ROOM DDR4_CH_M
J 0
(1800 2450);
PAINT ORANGE (1800 2450);
DISPLAY INVISIBLE (1800 2450);
FORCEADD SCONN288_H44441004..1
(-2500 3250);
FORCEPROP 2 LASTPIN (-3000 4900) $PN 234
J 2
(-3010 4910);
DISPLAY 0.617021 (-3010 4910);
PAINT ORANGE (-3010 4910);
FORCEPROP 1 LAST PART_NUMBER H44441-004
J 0
(-2950 1250);
DISPLAY 0.617021 (-2950 1250);
PAINT BLUE (-2950 1250);
FORCEPROP 1 LAST MATERIAL SCONN
J 0
(-2950 5100);
DISPLAY 0.617021 (-2950 5100);
PAINT SKYBLUE (-2950 5100);
FORCEPROP 2 LASTPIN (-3000 1750) $PN 146
J 2
(-3010 1760);
DISPLAY 0.617021 (-3010 1760);
PAINT ORANGE (-3010 1760);
FORCEPROP 2 LASTPIN (-3000 2100) $PN 284
J 2
(-3010 2110);
DISPLAY 0.617021 (-3010 2110);
PAINT ORANGE (-3010 2110);
FORCEPROP 2 LASTPIN (-3000 1900) $PN 285
J 2
(-3010 1910);
DISPLAY 0.617021 (-3010 1910);
PAINT ORANGE (-3010 1910);
FORCEPROP 2 LASTPIN (-3000 1850) $PN 141
J 2
(-3010 1860);
DISPLAY 0.617021 (-3010 1860);
PAINT ORANGE (-3010 1860);
FORCEPROP 2 LASTPIN (-3000 1450) $PN 230
J 2
(-3010 1460);
DISPLAY 0.617021 (-3010 1460);
PAINT ORANGE (-3010 1460);
FORCEPROP 2 LASTPIN (-3000 2050) $PN 238
J 2
(-3010 2060);
DISPLAY 0.617021 (-3010 2060);
PAINT ORANGE (-3010 2060);
FORCEPROP 2 LASTPIN (-3000 2000) $PN 140
J 2
(-3010 2010);
DISPLAY 0.617021 (-3010 2010);
PAINT ORANGE (-3010 2010);
FORCEPROP 2 LASTPIN (-3000 1950) $PN 139
J 2
(-3010 1960);
DISPLAY 0.617021 (-3010 1960);
PAINT ORANGE (-3010 1960);
FORCEPROP 2 LASTPIN (-3000 3400) $PN 237
J 2
(-3010 3410);
DISPLAY 0.617021 (-3010 3410);
PAINT ORANGE (-3010 3410);
FORCEPROP 2 LASTPIN (-3000 3350) $PN 93
J 2
(-3010 3360);
DISPLAY 0.617021 (-3010 3360);
PAINT ORANGE (-3010 3360);
FORCEPROP 2 LASTPIN (-3000 3300) $PN 89
J 2
(-3010 3310);
DISPLAY 0.617021 (-3010 3310);
PAINT ORANGE (-3010 3310);
FORCEPROP 2 LASTPIN (-3000 3250) $PN 84
J 2
(-3010 3260);
DISPLAY 0.617021 (-3010 3260);
PAINT ORANGE (-3010 3260);
FORCEPROP 2 LASTPIN (-3000 1650) $PN 144
J 2
(-3010 1660);
DISPLAY 0.617021 (-3010 1660);
PAINT ORANGE (-3010 1660);
FORCEPROP 2 LASTPIN (-3000 1600) $PN 227
J 2
(-3010 1610);
DISPLAY 0.617021 (-3010 1610);
PAINT ORANGE (-3010 1610);
FORCEPROP 2 LASTPIN (-3000 1550) $PN 205
J 2
(-3010 1560);
DISPLAY 0.617021 (-3010 1560);
PAINT ORANGE (-3010 1560);
FORCEPROP 2 LASTPIN (-3000 2350) $PN 58
J 2
(-3010 2360);
DISPLAY 0.617021 (-3010 2360);
PAINT ORANGE (-3010 2360);
FORCEPROP 2 LASTPIN (-3000 2400) $PN 222
J 2
(-3010 2410);
DISPLAY 0.617021 (-3010 2410);
PAINT ORANGE (-3010 2410);
FORCEPROP 2 LASTPIN (-3000 3000) $PN 91
J 2
(-3010 3010);
DISPLAY 0.617021 (-3010 3010);
PAINT ORANGE (-3010 3010);
FORCEPROP 2 LASTPIN (-3000 2950) $PN 87
J 2
(-3010 2960);
DISPLAY 0.617021 (-3010 2960);
PAINT ORANGE (-3010 2960);
FORCEPROP 2 LASTPIN (-3000 2300) $PN 78
J 2
(-3010 2310);
DISPLAY 0.617021 (-3010 2310);
PAINT ORANGE (-3010 2310);
FORCEPROP 2 LASTPIN (-2000 4900) $PN 280
J 0
(-1990 4910);
DISPLAY 0.617021 (-1990 4910);
PAINT ORANGE (-1990 4910);
FORCEPROP 2 LASTPIN (-2000 4850) $PN 135
J 0
(-1990 4860);
DISPLAY 0.617021 (-1990 4860);
PAINT ORANGE (-1990 4860);
FORCEPROP 2 LASTPIN (-2000 4800) $PN 273
J 0
(-1990 4810);
DISPLAY 0.617021 (-1990 4810);
PAINT ORANGE (-1990 4810);
FORCEPROP 2 LASTPIN (-2000 4750) $PN 128
J 0
(-1990 4760);
DISPLAY 0.617021 (-1990 4760);
PAINT ORANGE (-1990 4760);
FORCEPROP 2 LASTPIN (-2000 4700) $PN 282
J 0
(-1990 4710);
DISPLAY 0.617021 (-1990 4710);
PAINT ORANGE (-1990 4710);
FORCEPROP 2 LASTPIN (-2000 4650) $PN 137
J 0
(-1990 4660);
DISPLAY 0.617021 (-1990 4660);
PAINT ORANGE (-1990 4660);
FORCEPROP 2 LASTPIN (-2000 4600) $PN 275
J 0
(-1990 4610);
DISPLAY 0.617021 (-1990 4610);
PAINT ORANGE (-1990 4610);
FORCEPROP 2 LASTPIN (-2000 4550) $PN 130
J 0
(-1990 4560);
DISPLAY 0.617021 (-1990 4560);
PAINT ORANGE (-1990 4560);
FORCEPROP 2 LASTPIN (-2000 4500) $PN 269
J 0
(-1990 4510);
DISPLAY 0.617021 (-1990 4510);
PAINT ORANGE (-1990 4510);
FORCEPROP 2 LASTPIN (-2000 4450) $PN 124
J 0
(-1990 4460);
DISPLAY 0.617021 (-1990 4460);
PAINT ORANGE (-1990 4460);
FORCEPROP 2 LASTPIN (-2000 4400) $PN 262
J 0
(-1990 4410);
DISPLAY 0.617021 (-1990 4410);
PAINT ORANGE (-1990 4410);
FORCEPROP 2 LASTPIN (-2000 4350) $PN 117
J 0
(-1990 4360);
DISPLAY 0.617021 (-1990 4360);
PAINT ORANGE (-1990 4360);
FORCEPROP 2 LASTPIN (-2000 4300) $PN 271
J 0
(-1990 4310);
DISPLAY 0.617021 (-1990 4310);
PAINT ORANGE (-1990 4310);
FORCEPROP 2 LASTPIN (-2000 4250) $PN 126
J 0
(-1990 4260);
DISPLAY 0.617021 (-1990 4260);
PAINT ORANGE (-1990 4260);
FORCEPROP 2 LASTPIN (-2000 4200) $PN 264
J 0
(-1990 4210);
DISPLAY 0.617021 (-1990 4210);
PAINT ORANGE (-1990 4210);
FORCEPROP 2 LASTPIN (-2000 4150) $PN 119
J 0
(-1990 4160);
DISPLAY 0.617021 (-1990 4160);
PAINT ORANGE (-1990 4160);
FORCEPROP 2 LASTPIN (-2000 4100) $PN 258
J 0
(-1990 4110);
DISPLAY 0.617021 (-1990 4110);
PAINT ORANGE (-1990 4110);
FORCEPROP 2 LASTPIN (-2000 4050) $PN 113
J 0
(-1990 4060);
DISPLAY 0.617021 (-1990 4060);
PAINT ORANGE (-1990 4060);
FORCEPROP 2 LASTPIN (-2000 4000) $PN 251
J 0
(-1990 4010);
DISPLAY 0.617021 (-1990 4010);
PAINT ORANGE (-1990 4010);
FORCEPROP 2 LASTPIN (-2000 3950) $PN 106
J 0
(-1990 3960);
DISPLAY 0.617021 (-1990 3960);
PAINT ORANGE (-1990 3960);
FORCEPROP 2 LASTPIN (-2000 3900) $PN 260
J 0
(-1990 3910);
DISPLAY 0.617021 (-1990 3910);
PAINT ORANGE (-1990 3910);
FORCEPROP 2 LASTPIN (-2000 3850) $PN 115
J 0
(-1990 3860);
DISPLAY 0.617021 (-1990 3860);
PAINT ORANGE (-1990 3860);
FORCEPROP 2 LASTPIN (-2000 3800) $PN 253
J 0
(-1990 3810);
DISPLAY 0.617021 (-1990 3810);
PAINT ORANGE (-1990 3810);
FORCEPROP 2 LASTPIN (-2000 3650) $PN 102
J 0
(-1990 3660);
DISPLAY 0.617021 (-1990 3660);
PAINT ORANGE (-1990 3660);
FORCEPROP 2 LASTPIN (-2000 3600) $PN 240
J 0
(-1990 3610);
DISPLAY 0.617021 (-1990 3610);
PAINT ORANGE (-1990 3610);
FORCEPROP 2 LASTPIN (-2000 3500) $PN 249
J 0
(-1990 3510);
DISPLAY 0.617021 (-1990 3510);
PAINT ORANGE (-1990 3510);
FORCEPROP 2 LASTPIN (-2000 3450) $PN 104
J 0
(-1990 3460);
DISPLAY 0.617021 (-1990 3460);
PAINT ORANGE (-1990 3460);
FORCEPROP 2 LASTPIN (-2000 3350) $PN 97
J 0
(-1990 3360);
DISPLAY 0.617021 (-1990 3360);
PAINT ORANGE (-1990 3360);
FORCEPROP 2 LASTPIN (-2000 3300) $PN 188
J 0
(-1990 3310);
DISPLAY 0.617021 (-1990 3310);
PAINT ORANGE (-1990 3310);
FORCEPROP 2 LASTPIN (-2000 3250) $PN 43
J 0
(-1990 3260);
DISPLAY 0.617021 (-1990 3260);
PAINT ORANGE (-1990 3260);
FORCEPROP 2 LASTPIN (-2000 3200) $PN 181
J 0
(-1990 3210);
DISPLAY 0.617021 (-1990 3210);
PAINT ORANGE (-1990 3210);
FORCEPROP 2 LASTPIN (-2000 3150) $PN 36
J 0
(-1990 3160);
DISPLAY 0.617021 (-1990 3160);
PAINT ORANGE (-1990 3160);
FORCEPROP 2 LASTPIN (-2000 3100) $PN 190
J 0
(-1990 3110);
DISPLAY 0.617021 (-1990 3110);
PAINT ORANGE (-1990 3110);
FORCEPROP 2 LASTPIN (-2000 3050) $PN 45
J 0
(-1990 3060);
DISPLAY 0.617021 (-1990 3060);
PAINT ORANGE (-1990 3060);
FORCEPROP 2 LASTPIN (-2000 3000) $PN 183
J 0
(-1990 3010);
DISPLAY 0.617021 (-1990 3010);
PAINT ORANGE (-1990 3010);
FORCEPROP 2 LASTPIN (-2000 2950) $PN 38
J 0
(-1990 2960);
DISPLAY 0.617021 (-1990 2960);
PAINT ORANGE (-1990 2960);
FORCEPROP 2 LASTPIN (-2000 2900) $PN 177
J 0
(-1990 2910);
DISPLAY 0.617021 (-1990 2910);
PAINT ORANGE (-1990 2910);
FORCEPROP 2 LASTPIN (-2000 2850) $PN 32
J 0
(-1990 2860);
DISPLAY 0.617021 (-1990 2860);
PAINT ORANGE (-1990 2860);
FORCEPROP 2 LASTPIN (-2000 2800) $PN 170
J 0
(-1990 2810);
DISPLAY 0.617021 (-1990 2810);
PAINT ORANGE (-1990 2810);
FORCEPROP 2 LASTPIN (-2000 2750) $PN 25
J 0
(-1990 2760);
DISPLAY 0.617021 (-1990 2760);
PAINT ORANGE (-1990 2760);
FORCEPROP 2 LASTPIN (-2000 2700) $PN 179
J 0
(-1990 2710);
DISPLAY 0.617021 (-1990 2710);
PAINT ORANGE (-1990 2710);
FORCEPROP 2 LASTPIN (-2000 2650) $PN 34
J 0
(-1990 2660);
DISPLAY 0.617021 (-1990 2660);
PAINT ORANGE (-1990 2660);
FORCEPROP 2 LASTPIN (-2000 2600) $PN 172
J 0
(-1990 2610);
DISPLAY 0.617021 (-1990 2610);
PAINT ORANGE (-1990 2610);
FORCEPROP 2 LASTPIN (-2000 2550) $PN 27
J 0
(-1990 2560);
DISPLAY 0.617021 (-1990 2560);
PAINT ORANGE (-1990 2560);
FORCEPROP 2 LASTPIN (-2000 2500) $PN 166
J 0
(-1990 2510);
DISPLAY 0.617021 (-1990 2510);
PAINT ORANGE (-1990 2510);
FORCEPROP 2 LASTPIN (-2000 2450) $PN 21
J 0
(-1990 2460);
DISPLAY 0.617021 (-1990 2460);
PAINT ORANGE (-1990 2460);
FORCEPROP 2 LASTPIN (-2000 2400) $PN 159
J 0
(-1990 2410);
DISPLAY 0.617021 (-1990 2410);
PAINT ORANGE (-1990 2410);
FORCEPROP 2 LASTPIN (-2000 2350) $PN 14
J 0
(-1990 2360);
DISPLAY 0.617021 (-1990 2360);
PAINT ORANGE (-1990 2360);
FORCEPROP 2 LASTPIN (-2000 2300) $PN 168
J 0
(-1990 2310);
DISPLAY 0.617021 (-1990 2310);
PAINT ORANGE (-1990 2310);
FORCEPROP 2 LASTPIN (-2000 2250) $PN 23
J 0
(-1990 2260);
DISPLAY 0.617021 (-1990 2260);
PAINT ORANGE (-1990 2260);
FORCEPROP 2 LASTPIN (-2000 2200) $PN 161
J 0
(-1990 2210);
DISPLAY 0.617021 (-1990 2210);
PAINT ORANGE (-1990 2210);
FORCEPROP 2 LASTPIN (-2000 2150) $PN 16
J 0
(-1990 2160);
DISPLAY 0.617021 (-1990 2160);
PAINT ORANGE (-1990 2160);
FORCEPROP 2 LASTPIN (-2000 2100) $PN 155
J 0
(-1990 2110);
DISPLAY 0.617021 (-1990 2110);
PAINT ORANGE (-1990 2110);
FORCEPROP 2 LASTPIN (-2000 2050) $PN 10
J 0
(-1990 2060);
DISPLAY 0.617021 (-1990 2060);
PAINT ORANGE (-1990 2060);
FORCEPROP 2 LASTPIN (-2000 2000) $PN 148
J 0
(-1990 2010);
DISPLAY 0.617021 (-1990 2010);
PAINT ORANGE (-1990 2010);
FORCEPROP 2 LASTPIN (-2000 1950) $PN 3
J 0
(-1990 1960);
DISPLAY 0.617021 (-1990 1960);
PAINT ORANGE (-1990 1960);
FORCEPROP 2 LASTPIN (-2000 1900) $PN 157
J 0
(-1990 1910);
DISPLAY 0.617021 (-1990 1910);
PAINT ORANGE (-1990 1910);
FORCEPROP 2 LASTPIN (-2000 1850) $PN 12
J 0
(-1990 1860);
DISPLAY 0.617021 (-1990 1860);
PAINT ORANGE (-1990 1860);
FORCEPROP 2 LASTPIN (-2000 1800) $PN 150
J 0
(-1990 1810);
DISPLAY 0.617021 (-1990 1810);
PAINT ORANGE (-1990 1810);
FORCEPROP 2 LASTPIN (-2000 1750) $PN 5
J 0
(-1990 1760);
DISPLAY 0.617021 (-1990 1760);
PAINT ORANGE (-1990 1760);
FORCEPROP 2 LASTPIN (-3000 3150) $PN 203
J 2
(-3010 3160);
DISPLAY 0.617021 (-3010 3160);
PAINT ORANGE (-3010 3160);
FORCEPROP 2 LASTPIN (-3000 3100) $PN 60
J 2
(-3010 3110);
DISPLAY 0.617021 (-3010 3110);
PAINT ORANGE (-3010 3110);
FORCEPROP 2 LASTPIN (-3000 3700) $PN 218
J 2
(-3010 3710);
DISPLAY 0.617021 (-3010 3710);
PAINT ORANGE (-3010 3710);
FORCEPROP 2 LASTPIN (-3000 3650) $PN 219
J 2
(-3010 3660);
DISPLAY 0.617021 (-3010 3660);
PAINT ORANGE (-3010 3660);
FORCEPROP 2 LASTPIN (-3000 3600) $PN 74
J 2
(-3010 3610);
DISPLAY 0.617021 (-3010 3610);
PAINT ORANGE (-3010 3610);
FORCEPROP 2 LASTPIN (-3000 3550) $PN 75
J 2
(-3010 3560);
DISPLAY 0.617021 (-3010 3560);
PAINT ORANGE (-3010 3560);
FORCEPROP 2 LASTPIN (-3000 2850) $PN 199
J 2
(-3010 2860);
DISPLAY 0.617021 (-3010 2860);
PAINT ORANGE (-3010 2860);
FORCEPROP 2 LASTPIN (-3000 2800) $PN 54
J 2
(-3010 2810);
DISPLAY 0.617021 (-3010 2810);
PAINT ORANGE (-3010 2810);
FORCEPROP 2 LASTPIN (-3000 2750) $PN 192
J 2
(-3010 2760);
DISPLAY 0.617021 (-3010 2760);
PAINT ORANGE (-3010 2760);
FORCEPROP 2 LASTPIN (-3000 2700) $PN 47
J 2
(-3010 2710);
DISPLAY 0.617021 (-3010 2710);
PAINT ORANGE (-3010 2710);
FORCEPROP 2 LASTPIN (-3000 2650) $PN 201
J 2
(-3010 2660);
DISPLAY 0.617021 (-3010 2660);
PAINT ORANGE (-3010 2660);
FORCEPROP 2 LASTPIN (-3000 2600) $PN 56
J 2
(-3010 2610);
DISPLAY 0.617021 (-3010 2610);
PAINT ORANGE (-3010 2610);
FORCEPROP 2 LASTPIN (-3000 2550) $PN 194
J 2
(-3010 2560);
DISPLAY 0.617021 (-3010 2560);
PAINT ORANGE (-3010 2560);
FORCEPROP 2 LASTPIN (-3000 2500) $PN 49
J 2
(-3010 2510);
DISPLAY 0.617021 (-3010 2510);
PAINT ORANGE (-3010 2510);
FORCEPROP 2 LASTPIN (-3000 3450) $PN 235
J 2
(-3010 3460);
DISPLAY 0.617021 (-3010 3460);
PAINT ORANGE (-3010 3460);
FORCEPROP 2 LASTPIN (-3000 3850) $PN 207
J 2
(-3010 3860);
DISPLAY 0.617021 (-3010 3860);
PAINT ORANGE (-3010 3860);
FORCEPROP 2 LASTPIN (-3000 3800) $PN 63
J 2
(-3010 3810);
DISPLAY 0.617021 (-3010 3810);
PAINT ORANGE (-3010 3810);
FORCEPROP 2 LASTPIN (-3000 3950) $PN 224
J 2
(-3010 3960);
DISPLAY 0.617021 (-3010 3960);
PAINT ORANGE (-3010 3960);
FORCEPROP 2 LASTPIN (-3000 3900) $PN 81
J 2
(-3010 3910);
DISPLAY 0.617021 (-3010 3910);
PAINT ORANGE (-3010 3910);
FORCEPROP 2 LASTPIN (-3000 2250) $PN 208
J 2
(-3010 2260);
DISPLAY 0.617021 (-3010 2260);
PAINT ORANGE (-3010 2260);
FORCEPROP 2 LASTPIN (-3000 2200) $PN 62
J 2
(-3010 2210);
DISPLAY 0.617021 (-3010 2210);
PAINT ORANGE (-3010 2210);
FORCEPROP 2 LASTPIN (-3000 4850) $PN 82
J 2
(-3010 4860);
DISPLAY 0.617021 (-3010 4860);
PAINT ORANGE (-3010 4860);
FORCEPROP 2 LASTPIN (-3000 4800) $PN 86
J 2
(-3010 4810);
DISPLAY 0.617021 (-3010 4810);
PAINT ORANGE (-3010 4810);
FORCEPROP 2 LASTPIN (-3000 4750) $PN 228
J 2
(-3010 4760);
DISPLAY 0.617021 (-3010 4760);
PAINT ORANGE (-3010 4760);
FORCEPROP 2 LASTPIN (-3000 4650) $PN 65
J 2
(-3010 4660);
DISPLAY 0.617021 (-3010 4660);
PAINT ORANGE (-3010 4660);
FORCEPROP 2 LASTPIN (-3000 4500) $PN 66
J 2
(-3010 4510);
DISPLAY 0.617021 (-3010 4510);
PAINT ORANGE (-3010 4510);
FORCEPROP 2 LASTPIN (-3000 4450) $PN 68
J 2
(-3010 4460);
DISPLAY 0.617021 (-3010 4460);
PAINT ORANGE (-3010 4460);
FORCEPROP 2 LASTPIN (-3000 4400) $PN 211
J 2
(-3010 4410);
DISPLAY 0.617021 (-3010 4410);
PAINT ORANGE (-3010 4410);
FORCEPROP 2 LASTPIN (-3000 4350) $PN 69
J 2
(-3010 4360);
DISPLAY 0.617021 (-3010 4360);
PAINT ORANGE (-3010 4360);
FORCEPROP 2 LASTPIN (-3000 4300) $PN 213
J 2
(-3010 4310);
DISPLAY 0.617021 (-3010 4310);
PAINT ORANGE (-3010 4310);
FORCEPROP 2 LASTPIN (-3000 4250) $PN 214
J 2
(-3010 4260);
DISPLAY 0.617021 (-3010 4260);
PAINT ORANGE (-3010 4260);
FORCEPROP 2 LASTPIN (-3000 4200) $PN 71
J 2
(-3010 4210);
DISPLAY 0.617021 (-3010 4210);
PAINT ORANGE (-3010 4210);
FORCEPROP 2 LASTPIN (-3000 4150) $PN 216
J 2
(-3010 4160);
DISPLAY 0.617021 (-3010 4160);
PAINT ORANGE (-3010 4160);
FORCEPROP 2 LASTPIN (-3000 4100) $PN 72
J 2
(-3010 4110);
DISPLAY 0.617021 (-3010 4110);
PAINT ORANGE (-3010 4110);
FORCEPROP 2 LASTPIN (-3000 4050) $PN 79
J 2
(-3010 4060);
DISPLAY 0.617021 (-3010 4060);
PAINT ORANGE (-3010 4060);
FORCEPROP 2 LASTPIN (-2000 3700) $PN 247
J 0
(-1990 3710);
DISPLAY 0.617021 (-1990 3710);
PAINT ORANGE (-1990 3710);
FORCEPROP 2 LASTPIN (-2000 3750) $PN 108
J 0
(-1990 3760);
DISPLAY 0.617021 (-1990 3760);
PAINT ORANGE (-1990 3760);
FORCEPROP 2 LASTPIN (-3000 4550) $PN 225
J 2
(-3010 4560);
DISPLAY 0.617021 (-3010 4560);
PAINT ORANGE (-3010 4560);
FORCEPROP 2 LASTPIN (-3000 4600) $PN 210
J 2
(-3010 4610);
DISPLAY 0.617021 (-3010 4610);
PAINT ORANGE (-3010 4610);
FORCEPROP 2 LASTPIN (-3000 4700) $PN 232
J 2
(-3010 4710);
DISPLAY 0.617021 (-3010 4710);
PAINT ORANGE (-3010 4710);
FORCEPROP 1 LAST LOCATION J1A1
J 0
(-2950 5150);
DISPLAY 0.617021 (-2950 5150);
PAINT AQUA (-2950 5150);
FORCEPROP 2 LASTPIN (-2000 3400) $PN 242
J 0
(-1990 3410);
DISPLAY 0.617021 (-1990 3410);
PAINT ORANGE (-1990 3410);
FORCEPROP 2 LASTPIN (-2000 3550) $PN 95
J 0
(-1990 3560);
DISPLAY 0.617021 (-1990 3560);
PAINT ORANGE (-1990 3560);
FORCEPROP 1 LAST PACK_TYPE PIP
J 0
(-2950 5200);
PAINT SKYBLUE (-2950 5200);
DISPLAY INVISIBLE (-2950 5200);
FORCEPROP 2 LAST BOM_COST MEM
J 0
(-2500 3250);
PAINT ORANGE (-2500 3250);
DISPLAY INVISIBLE (-2500 3250);
FORCEPROP 2 LAST CDS_LIB mstr_sconn
J 0
(-2500 3250);
PAINT ORANGE (-2500 3250);
DISPLAY INVISIBLE (-2500 3250);
FORCEPROP 2 LAST SEC_TYPE PIP
J 0
(-2950 5200);
DISPLAY 1.021277 (-2950 5200);
PAINT ORANGE (-2950 5200);
DISPLAY INVISIBLE (-2950 5200);
FORCEPROP 2 LAST SEC 1
J 0
(-2950 5200);
DISPLAY 0.680851 (-2950 5200);
PAINT MONO (-2950 5200);
DISPLAY INVISIBLE (-2950 5200);
FORCEPROP 2 LAST CDS_LOCATION J1A1
J 0
(-2950 5150);
DISPLAY 0.617021 (-2950 5150);
PAINT AQUA (-2950 5150);
DISPLAY INVISIBLE (-2950 5150);
FORCEPROP 1 LAST PATH I186
J 0
(-2500 5100);
PAINT GREEN (-2500 5100);
DISPLAY INVISIBLE (-2500 5100);
FORCEPROP 2 LAST ROOM DDR4_CH_M
J 0
(-2500 3250);
PAINT ORANGE (-2500 3250);
DISPLAY INVISIBLE (-2500 3250);
FORCEADD SCONN288_H44441004..2
(0 4300);
FORCEPROP 1 LAST LOCATION J1A1
J 0
(-400 5400);
DISPLAY 0.617021 (-400 5400);
PAINT AQUA (-400 5400);
FORCEPROP 1 LAST PART_NUMBER H44441-004
J 0
(-400 3200);
DISPLAY 0.617021 (-400 3200);
PAINT BLUE (-400 3200);
FORCEPROP 1 LAST MATERIAL SCONN
J 0
(-400 5350);
DISPLAY 0.617021 (-400 5350);
PAINT SKYBLUE (-400 5350);
FORCEPROP 2 LASTPIN (450 5150) $PN 51
J 0
(460 5160);
DISPLAY 0.617021 (460 5160);
PAINT ORANGE (460 5160);
FORCEPROP 2 LASTPIN (450 5100) $PN 52
J 0
(460 5110);
DISPLAY 0.617021 (460 5110);
PAINT ORANGE (460 5110);
FORCEPROP 2 LASTPIN (450 5050) $PN 132
J 0
(460 5060);
DISPLAY 0.617021 (460 5060);
PAINT ORANGE (460 5060);
FORCEPROP 2 LASTPIN (450 5000) $PN 133
J 0
(460 5010);
DISPLAY 0.617021 (460 5010);
PAINT ORANGE (460 5010);
FORCEPROP 2 LASTPIN (450 4950) $PN 121
J 0
(460 4960);
DISPLAY 0.617021 (460 4960);
PAINT ORANGE (460 4960);
FORCEPROP 2 LASTPIN (450 4900) $PN 122
J 0
(460 4910);
DISPLAY 0.617021 (460 4910);
PAINT ORANGE (460 4910);
FORCEPROP 2 LASTPIN (450 4850) $PN 110
J 0
(460 4860);
DISPLAY 0.617021 (460 4860);
PAINT ORANGE (460 4860);
FORCEPROP 2 LASTPIN (450 4800) $PN 111
J 0
(460 4810);
DISPLAY 0.617021 (460 4810);
PAINT ORANGE (460 4810);
FORCEPROP 2 LASTPIN (450 4750) $PN 99
J 0
(460 4760);
DISPLAY 0.617021 (460 4760);
PAINT ORANGE (460 4760);
FORCEPROP 2 LASTPIN (450 4700) $PN 100
J 0
(460 4710);
DISPLAY 0.617021 (460 4710);
PAINT ORANGE (460 4710);
FORCEPROP 2 LASTPIN (450 4650) $PN 40
J 0
(460 4660);
DISPLAY 0.617021 (460 4660);
PAINT ORANGE (460 4660);
FORCEPROP 2 LASTPIN (450 4600) $PN 41
J 0
(460 4610);
DISPLAY 0.617021 (460 4610);
PAINT ORANGE (460 4610);
FORCEPROP 2 LASTPIN (450 4550) $PN 29
J 0
(460 4560);
DISPLAY 0.617021 (460 4560);
PAINT ORANGE (460 4560);
FORCEPROP 2 LASTPIN (450 4500) $PN 30
J 0
(460 4510);
DISPLAY 0.617021 (460 4510);
PAINT ORANGE (460 4510);
FORCEPROP 2 LASTPIN (450 4450) $PN 18
J 0
(460 4460);
DISPLAY 0.617021 (460 4460);
PAINT ORANGE (460 4460);
FORCEPROP 2 LASTPIN (450 4400) $PN 19
J 0
(460 4410);
DISPLAY 0.617021 (460 4410);
PAINT ORANGE (460 4410);
FORCEPROP 2 LASTPIN (450 4350) $PN 7
J 0
(460 4360);
DISPLAY 0.617021 (460 4360);
PAINT ORANGE (460 4360);
FORCEPROP 2 LASTPIN (450 4300) $PN 8
J 0
(460 4310);
DISPLAY 0.617021 (460 4310);
PAINT ORANGE (460 4310);
FORCEPROP 2 LASTPIN (450 4250) $PN 197
J 0
(460 4260);
DISPLAY 0.617021 (460 4260);
PAINT ORANGE (460 4260);
FORCEPROP 2 LASTPIN (450 4200) $PN 196
J 0
(460 4210);
DISPLAY 0.617021 (460 4210);
PAINT ORANGE (460 4210);
FORCEPROP 2 LASTPIN (450 4150) $PN 278
J 0
(460 4160);
DISPLAY 0.617021 (460 4160);
PAINT ORANGE (460 4160);
FORCEPROP 2 LASTPIN (450 4100) $PN 277
J 0
(460 4110);
DISPLAY 0.617021 (460 4110);
PAINT ORANGE (460 4110);
FORCEPROP 2 LASTPIN (450 4050) $PN 267
J 0
(460 4060);
DISPLAY 0.617021 (460 4060);
PAINT ORANGE (460 4060);
FORCEPROP 2 LASTPIN (450 4000) $PN 266
J 0
(460 4010);
DISPLAY 0.617021 (460 4010);
PAINT ORANGE (460 4010);
FORCEPROP 2 LASTPIN (450 3950) $PN 256
J 0
(460 3960);
DISPLAY 0.617021 (460 3960);
PAINT ORANGE (460 3960);
FORCEPROP 2 LASTPIN (450 3900) $PN 255
J 0
(460 3910);
DISPLAY 0.617021 (460 3910);
PAINT ORANGE (460 3910);
FORCEPROP 2 LASTPIN (450 3850) $PN 245
J 0
(460 3860);
DISPLAY 0.617021 (460 3860);
PAINT ORANGE (460 3860);
FORCEPROP 2 LASTPIN (450 3800) $PN 244
J 0
(460 3810);
DISPLAY 0.617021 (460 3810);
PAINT ORANGE (460 3810);
FORCEPROP 2 LASTPIN (450 3750) $PN 186
J 0
(460 3760);
DISPLAY 0.617021 (460 3760);
PAINT ORANGE (460 3760);
FORCEPROP 2 LASTPIN (450 3700) $PN 185
J 0
(460 3710);
DISPLAY 0.617021 (460 3710);
PAINT ORANGE (460 3710);
FORCEPROP 2 LASTPIN (450 3650) $PN 175
J 0
(460 3660);
DISPLAY 0.617021 (460 3660);
PAINT ORANGE (460 3660);
FORCEPROP 2 LASTPIN (450 3600) $PN 174
J 0
(460 3610);
DISPLAY 0.617021 (460 3610);
PAINT ORANGE (460 3610);
FORCEPROP 2 LASTPIN (450 3550) $PN 164
J 0
(460 3560);
DISPLAY 0.617021 (460 3560);
PAINT ORANGE (460 3560);
FORCEPROP 2 LASTPIN (450 3500) $PN 163
J 0
(460 3510);
DISPLAY 0.617021 (460 3510);
PAINT ORANGE (460 3510);
FORCEPROP 2 LASTPIN (450 3450) $PN 153
J 0
(460 3460);
DISPLAY 0.617021 (460 3460);
PAINT ORANGE (460 3460);
FORCEPROP 2 LASTPIN (450 3400) $PN 152
J 0
(460 3410);
DISPLAY 0.617021 (460 3410);
PAINT ORANGE (460 3410);
FORCEPROP 1 LAST PACK_TYPE PIP
J 0
(-400 5450);
PAINT SKYBLUE (-400 5450);
DISPLAY INVISIBLE (-400 5450);
FORCEPROP 2 LAST BOM_COST MEM
J 0
(0 4300);
PAINT ORANGE (0 4300);
DISPLAY INVISIBLE (0 4300);
FORCEPROP 2 LAST CDS_LIB mstr_sconn
J 0
(0 4300);
PAINT ORANGE (0 4300);
DISPLAY INVISIBLE (0 4300);
FORCEPROP 2 LAST SEC_TYPE PIP
J 0
(-400 5450);
DISPLAY 1.021277 (-400 5450);
PAINT ORANGE (-400 5450);
DISPLAY INVISIBLE (-400 5450);
FORCEPROP 2 LAST SEC 2
J 0
(-400 5450);
DISPLAY 0.680851 (-400 5450);
PAINT MONO (-400 5450);
DISPLAY INVISIBLE (-400 5450);
FORCEPROP 2 LAST CDS_LOCATION J1A1
J 0
(-400 5400);
DISPLAY 0.617021 (-400 5400);
PAINT AQUA (-400 5400);
DISPLAY INVISIBLE (-400 5400);
FORCEPROP 1 LAST PATH I187
J 0
(0 5350);
PAINT GREEN (0 5350);
DISPLAY INVISIBLE (0 5350);
FORCEPROP 2 LAST ROOM DDR4_CH_M
J 0
(0 4300);
PAINT ORANGE (0 4300);
DISPLAY INVISIBLE (0 4300);
FORCEADD P12V_NVDIMM_KLM..1
(300 3025);
FORCEPROP 3 LASTPIN (300 2975) SIG_NAME P12V_NVDIMM_KLM\g
J 0
(310 2985);
DISPLAY 0.659574 (310 2985);
PAINT MONO (310 2985);
DISPLAY INVISIBLE (310 2985);
FORCEPROP 1 LAST VOLTAGE 12.0
J 0
(255 2982);
DISPLAY 0.340426 (255 2982);
PAINT SKYBLUE (255 2982);
DISPLAY INVISIBLE (255 2982);
FORCEPROP 2 LAST CDS_LIB mstr_symbols
J 0
(300 3025);
PAINT ORANGE (300 3025);
DISPLAY INVISIBLE (300 3025);
FORCEPROP 1 LAST BODY_TYPE PLUMBING
J 0
(255 2982);
DISPLAY 0.340426 (255 2982);
PAINT GREEN (255 2982);
DISPLAY INVISIBLE (255 2982);
FORCEPROP 1 LAST PATH I188
J 0
(350 3050);
DISPLAY 0.872340 (350 3050);
PAINT AQUA (350 3050);
DISPLAY INVISIBLE (350 3050);
FORCEPROP 1 LAST HDL_POWER P12V_NVDIMM_KLM
J 1
(300 3075);
DISPLAY 0.872340 (300 3075);
PAINT GREEN (300 3075);
DISPLAY INVISIBLE (300 3075);
FORCEADD TAP..6
R 2
(900 3800);
FORCEPROP 3 LASTPIN (850 3800) SIG_NAME M_M_DQS_DN<4>
J 0
(860 3810);
DISPLAY 0.659574 (860 3810);
PAINT MONO (860 3810);
DISPLAY INVISIBLE (860 3810);
FORCEPROP 1 LASTPIN (850 3800) BN 4
J 2
(900 3810);
DISPLAY 0.617021 (900 3810);
PAINT PINK (900 3810);
FORCEPROP 2 LAST CDS_LIB mstr_standard
J 0
(900 3800);
DISPLAY 0.787234 (900 3800);
PAINT MONO (900 3800);
DISPLAY INVISIBLE (900 3800);
FORCEPROP 1 LAST BODY_TYPE PLUMBING
J 2
(900 3750);
DISPLAY 1.234043 (900 3750);
PAINT GREEN (900 3750);
DISPLAY INVISIBLE (900 3750);
FORCEPROP 1 LAST HDL_TAP TRUE
J 2
(575 3675);
DISPLAY 1.234043 (575 3675);
PAINT GREEN (575 3675);
DISPLAY INVISIBLE (575 3675);
FORCEPROP 1 LAST PATH I19
J 2
(900 3800);
DISPLAY 0.936170 (900 3800);
PAINT GREEN (900 3800);
DISPLAY INVISIBLE (900 3800);
FORCEADD OFFPAGE..3
(1600 5150);
FORCEPROP 2 LAST $XR1 88 
J 0
(1904 5150);
DISPLAY 0.638298 (1904 5150);
PAINT MONO (1904 5150);
FORCEPROP 2 LAST $XR0 62 
J 0
(1814 5150);
DISPLAY 0.638298 (1814 5150);
PAINT MONO (1814 5150);
FORCEPROP 2 LAST CDS_LIB mstr_standard
J 0
(1600 5150);
DISPLAY 0.787234 (1600 5150);
PAINT MONO (1600 5150);
DISPLAY INVISIBLE (1600 5150);
FORCEPROP 1 LAST OFFPAGE TRUE
J 0
(1925 5025);
DISPLAY 0.936170 (1925 5025);
PAINT GREEN (1925 5025);
DISPLAY INVISIBLE (1925 5025);
FORCEPROP 1 LAST COMMENT_BODY TRUE
J 0
(1550 5050);
DISPLAY 0.936170 (1550 5050);
PAINT GREEN (1550 5050);
DISPLAY INVISIBLE (1550 5050);
FORCEPROP 2 LAST PATH I2
J 0
(1800 5225);
DISPLAY 0.787234 (1800 5225);
PAINT MONO (1800 5225);
DISPLAY INVISIBLE (1800 5225);
FORCEADD TAP..6
R 2
(900 3700);
FORCEPROP 3 LASTPIN (850 3700) SIG_NAME M_M_DQS_DN<3>
J 0
(860 3710);
DISPLAY 0.659574 (860 3710);
PAINT MONO (860 3710);
DISPLAY INVISIBLE (860 3710);
FORCEPROP 1 LASTPIN (850 3700) BN 3
J 2
(900 3710);
DISPLAY 0.617021 (900 3710);
PAINT PINK (900 3710);
FORCEPROP 2 LAST CDS_LIB mstr_standard
J 0
(900 3700);
DISPLAY 0.787234 (900 3700);
PAINT MONO (900 3700);
DISPLAY INVISIBLE (900 3700);
FORCEPROP 1 LAST BODY_TYPE PLUMBING
J 2
(900 3650);
DISPLAY 1.234043 (900 3650);
PAINT GREEN (900 3650);
DISPLAY INVISIBLE (900 3650);
FORCEPROP 1 LAST HDL_TAP TRUE
J 2
(575 3575);
DISPLAY 1.234043 (575 3575);
PAINT GREEN (575 3575);
DISPLAY INVISIBLE (575 3575);
FORCEPROP 1 LAST PATH I20
J 2
(900 3700);
DISPLAY 0.936170 (900 3700);
PAINT GREEN (900 3700);
DISPLAY INVISIBLE (900 3700);
FORCEADD TAP..6
R 2
(900 3500);
FORCEPROP 3 LASTPIN (850 3500) SIG_NAME M_M_DQS_DN<1>
J 0
(860 3510);
DISPLAY 0.659574 (860 3510);
PAINT MONO (860 3510);
DISPLAY INVISIBLE (860 3510);
FORCEPROP 1 LASTPIN (850 3500) BN 1
J 2
(900 3510);
DISPLAY 0.617021 (900 3510);
PAINT PINK (900 3510);
FORCEPROP 2 LAST CDS_LIB mstr_standard
J 0
(900 3500);
DISPLAY 0.787234 (900 3500);
PAINT MONO (900 3500);
DISPLAY INVISIBLE (900 3500);
FORCEPROP 1 LAST BODY_TYPE PLUMBING
J 2
(900 3450);
DISPLAY 1.234043 (900 3450);
PAINT GREEN (900 3450);
DISPLAY INVISIBLE (900 3450);
FORCEPROP 1 LAST HDL_TAP TRUE
J 2
(575 3375);
DISPLAY 1.234043 (575 3375);
PAINT GREEN (575 3375);
DISPLAY INVISIBLE (575 3375);
FORCEPROP 1 LAST PATH I21
J 2
(900 3500);
DISPLAY 0.936170 (900 3500);
PAINT GREEN (900 3500);
DISPLAY INVISIBLE (900 3500);
FORCEADD TAP..6
R 2
(900 3600);
FORCEPROP 3 LASTPIN (850 3600) SIG_NAME M_M_DQS_DN<2>
J 0
(860 3610);
DISPLAY 0.659574 (860 3610);
PAINT MONO (860 3610);
DISPLAY INVISIBLE (860 3610);
FORCEPROP 1 LASTPIN (850 3600) BN 2
J 2
(900 3610);
DISPLAY 0.617021 (900 3610);
PAINT PINK (900 3610);
FORCEPROP 2 LAST CDS_LIB mstr_standard
J 0
(900 3600);
DISPLAY 0.787234 (900 3600);
PAINT MONO (900 3600);
DISPLAY INVISIBLE (900 3600);
FORCEPROP 1 LAST BODY_TYPE PLUMBING
J 2
(900 3550);
DISPLAY 1.234043 (900 3550);
PAINT GREEN (900 3550);
DISPLAY INVISIBLE (900 3550);
FORCEPROP 1 LAST HDL_TAP TRUE
J 2
(575 3475);
DISPLAY 1.234043 (575 3475);
PAINT GREEN (575 3475);
DISPLAY INVISIBLE (575 3475);
FORCEPROP 1 LAST PATH I22
J 2
(900 3600);
DISPLAY 0.936170 (900 3600);
PAINT GREEN (900 3600);
DISPLAY INVISIBLE (900 3600);
FORCEADD TAP..6
R 2
(900 3400);
FORCEPROP 3 LASTPIN (850 3400) SIG_NAME M_M_DQS_DN<0>
J 0
(860 3410);
DISPLAY 0.659574 (860 3410);
PAINT MONO (860 3410);
DISPLAY INVISIBLE (860 3410);
FORCEPROP 1 LASTPIN (850 3400) BN 0
J 2
(900 3410);
DISPLAY 0.617021 (900 3410);
PAINT PINK (900 3410);
FORCEPROP 2 LAST CDS_LIB mstr_standard
J 0
(900 3400);
DISPLAY 0.787234 (900 3400);
PAINT MONO (900 3400);
DISPLAY INVISIBLE (900 3400);
FORCEPROP 1 LAST BODY_TYPE PLUMBING
J 2
(900 3350);
DISPLAY 1.234043 (900 3350);
PAINT GREEN (900 3350);
DISPLAY INVISIBLE (900 3350);
FORCEPROP 1 LAST HDL_TAP TRUE
J 2
(575 3275);
DISPLAY 1.234043 (575 3275);
PAINT GREEN (575 3275);
DISPLAY INVISIBLE (575 3275);
FORCEPROP 1 LAST PATH I23
J 2
(900 3400);
DISPLAY 0.936170 (900 3400);
PAINT GREEN (900 3400);
DISPLAY INVISIBLE (900 3400);
FORCEADD GND..1
R 2
(1100 1150);
FORCEPROP 3 LASTPIN (1100 1200) SIG_NAME GND\g
J 0
(1110 1210);
DISPLAY 0.659574 (1110 1210);
PAINT MONO (1110 1210);
DISPLAY INVISIBLE (1110 1210);
FORCEPROP 1 LAST VOLTAGE 0
J 0
(1100 1150);
PAINT SKYBLUE (1100 1150);
DISPLAY INVISIBLE (1100 1150);
FORCEPROP 2 LAST BOM_COST MEM
J 0
(1100 1155);
PAINT ORANGE (1100 1155);
DISPLAY INVISIBLE (1100 1155);
FORCEPROP 1 LAST SIZE 1B
J 2
(1025 1100);
DISPLAY 1.170213 (1025 1100);
PAINT GREEN (1025 1100);
DISPLAY INVISIBLE (1025 1100);
FORCEPROP 2 LAST CDS_LIB mstr_symbols
J 0
(1100 1150);
DISPLAY 0.787234 (1100 1150);
PAINT MONO (1100 1150);
DISPLAY INVISIBLE (1100 1150);
FORCEPROP 1 LAST BODY_TYPE PLUMBING
J 2
(1145 1107);
DISPLAY 0.340426 (1145 1107);
PAINT GREEN (1145 1107);
DISPLAY INVISIBLE (1145 1107);
FORCEPROP 1 LAST PATH I26
J 2
(1025 1150);
DISPLAY 0.936170 (1025 1150);
PAINT GREEN (1025 1150);
DISPLAY INVISIBLE (1025 1150);
FORCEPROP 2 LAST ROOM DDR4_CH_D
J 0
(1100 1155);
PAINT ORANGE (1100 1155);
DISPLAY INVISIBLE (1100 1155);
FORCEPROP 1 LAST HDL_POWER GND
J 2
(1100 1300);
DISPLAY 0.553191 (1100 1300);
PAINT GREEN (1100 1300);
DISPLAY INVISIBLE (1100 1300);
FORCEADD TAP..6
R 2
(700 5150);
FORCEPROP 3 LASTPIN (650 5150) SIG_NAME M_M_DQS_DP<17>
J 0
(660 5160);
DISPLAY 0.659574 (660 5160);
PAINT MONO (660 5160);
DISPLAY INVISIBLE (660 5160);
FORCEPROP 1 LASTPIN (650 5150) BN 17
J 2
(700 5160);
DISPLAY 0.617021 (700 5160);
PAINT PINK (700 5160);
FORCEPROP 2 LAST CDS_LIB mstr_standard
J 2
(700 5150);
DISPLAY 0.787234 (700 5150);
PAINT MONO (700 5150);
DISPLAY INVISIBLE (700 5150);
FORCEPROP 1 LAST BODY_TYPE PLUMBING
J 2
(700 5100);
DISPLAY 1.234043 (700 5100);
PAINT GREEN (700 5100);
DISPLAY INVISIBLE (700 5100);
FORCEPROP 1 LAST HDL_TAP TRUE
J 2
(375 5025);
DISPLAY 1.234043 (375 5025);
PAINT GREEN (375 5025);
DISPLAY INVISIBLE (375 5025);
FORCEPROP 1 LAST PATH I27
J 2
(700 5150);
DISPLAY 0.936170 (700 5150);
PAINT GREEN (700 5150);
DISPLAY INVISIBLE (700 5150);
FORCEADD TAP..6
R 2
(700 5050);
FORCEPROP 3 LASTPIN (650 5050) SIG_NAME M_M_DQS_DP<16>
J 0
(660 5060);
DISPLAY 0.659574 (660 5060);
PAINT MONO (660 5060);
DISPLAY INVISIBLE (660 5060);
FORCEPROP 1 LASTPIN (650 5050) BN 16
J 2
(700 5060);
DISPLAY 0.617021 (700 5060);
PAINT PINK (700 5060);
FORCEPROP 2 LAST CDS_LIB mstr_standard
J 0
(700 5050);
DISPLAY 0.787234 (700 5050);
PAINT MONO (700 5050);
DISPLAY INVISIBLE (700 5050);
FORCEPROP 1 LAST BODY_TYPE PLUMBING
J 2
(700 5000);
DISPLAY 1.234043 (700 5000);
PAINT GREEN (700 5000);
DISPLAY INVISIBLE (700 5000);
FORCEPROP 1 LAST HDL_TAP TRUE
J 2
(375 4925);
DISPLAY 1.234043 (375 4925);
PAINT GREEN (375 4925);
DISPLAY INVISIBLE (375 4925);
FORCEPROP 1 LAST PATH I28
J 2
(700 5050);
DISPLAY 0.936170 (700 5050);
PAINT GREEN (700 5050);
DISPLAY INVISIBLE (700 5050);
FORCEADD TAP..6
R 2
(700 4750);
FORCEPROP 3 LASTPIN (650 4750) SIG_NAME M_M_DQS_DP<13>
J 0
(660 4760);
DISPLAY 0.659574 (660 4760);
PAINT MONO (660 4760);
DISPLAY INVISIBLE (660 4760);
FORCEPROP 1 LASTPIN (650 4750) BN 13
J 2
(700 4760);
DISPLAY 0.617021 (700 4760);
PAINT PINK (700 4760);
FORCEPROP 2 LAST CDS_LIB mstr_standard
J 0
(700 4750);
DISPLAY 0.787234 (700 4750);
PAINT MONO (700 4750);
DISPLAY INVISIBLE (700 4750);
FORCEPROP 1 LAST BODY_TYPE PLUMBING
J 2
(700 4700);
DISPLAY 1.234043 (700 4700);
PAINT GREEN (700 4700);
DISPLAY INVISIBLE (700 4700);
FORCEPROP 1 LAST HDL_TAP TRUE
J 2
(375 4625);
DISPLAY 1.234043 (375 4625);
PAINT GREEN (375 4625);
DISPLAY INVISIBLE (375 4625);
FORCEPROP 1 LAST PATH I29
J 2
(700 4750);
DISPLAY 0.936170 (700 4750);
PAINT GREEN (700 4750);
DISPLAY INVISIBLE (700 4750);
FORCEADD TAP..6
R 2
(900 5100);
FORCEPROP 3 LASTPIN (850 5100) SIG_NAME M_M_DQS_DN<17>
J 0
(860 5110);
DISPLAY 0.659574 (860 5110);
PAINT MONO (860 5110);
DISPLAY INVISIBLE (860 5110);
FORCEPROP 1 LASTPIN (850 5100) BN 17
J 2
(900 5110);
DISPLAY 0.617021 (900 5110);
PAINT PINK (900 5110);
FORCEPROP 2 LAST CDS_LIB mstr_standard
J 2
(900 5100);
DISPLAY 0.787234 (900 5100);
PAINT MONO (900 5100);
DISPLAY INVISIBLE (900 5100);
FORCEPROP 1 LAST BODY_TYPE PLUMBING
J 2
(900 5050);
DISPLAY 1.234043 (900 5050);
PAINT GREEN (900 5050);
DISPLAY INVISIBLE (900 5050);
FORCEPROP 1 LAST HDL_TAP TRUE
J 2
(575 4975);
DISPLAY 1.234043 (575 4975);
PAINT GREEN (575 4975);
DISPLAY INVISIBLE (575 4975);
FORCEPROP 1 LAST PATH I3
J 2
(900 5100);
DISPLAY 0.936170 (900 5100);
PAINT GREEN (900 5100);
DISPLAY INVISIBLE (900 5100);
FORCEADD TAP..6
R 2
(700 4650);
FORCEPROP 3 LASTPIN (650 4650) SIG_NAME M_M_DQS_DP<12>
J 0
(660 4660);
DISPLAY 0.659574 (660 4660);
PAINT MONO (660 4660);
DISPLAY INVISIBLE (660 4660);
FORCEPROP 1 LASTPIN (650 4650) BN 12
J 2
(700 4660);
DISPLAY 0.617021 (700 4660);
PAINT PINK (700 4660);
FORCEPROP 2 LAST CDS_LIB mstr_standard
J 0
(700 4650);
DISPLAY 0.787234 (700 4650);
PAINT MONO (700 4650);
DISPLAY INVISIBLE (700 4650);
FORCEPROP 1 LAST BODY_TYPE PLUMBING
J 2
(700 4600);
DISPLAY 1.234043 (700 4600);
PAINT GREEN (700 4600);
DISPLAY INVISIBLE (700 4600);
FORCEPROP 1 LAST HDL_TAP TRUE
J 2
(375 4525);
DISPLAY 1.234043 (375 4525);
PAINT GREEN (375 4525);
DISPLAY INVISIBLE (375 4525);
FORCEPROP 1 LAST PATH I30
J 2
(700 4650);
DISPLAY 0.936170 (700 4650);
PAINT GREEN (700 4650);
DISPLAY INVISIBLE (700 4650);
FORCEADD TAP..6
R 2
(700 4550);
FORCEPROP 3 LASTPIN (650 4550) SIG_NAME M_M_DQS_DP<11>
J 0
(660 4560);
DISPLAY 0.659574 (660 4560);
PAINT MONO (660 4560);
DISPLAY INVISIBLE (660 4560);
FORCEPROP 1 LASTPIN (650 4550) BN 11
J 2
(700 4560);
DISPLAY 0.617021 (700 4560);
PAINT PINK (700 4560);
FORCEPROP 2 LAST CDS_LIB mstr_standard
J 0
(700 4550);
DISPLAY 0.787234 (700 4550);
PAINT MONO (700 4550);
DISPLAY INVISIBLE (700 4550);
FORCEPROP 1 LAST BODY_TYPE PLUMBING
J 2
(700 4500);
DISPLAY 1.234043 (700 4500);
PAINT GREEN (700 4500);
DISPLAY INVISIBLE (700 4500);
FORCEPROP 1 LAST HDL_TAP TRUE
J 2
(375 4425);
DISPLAY 1.234043 (375 4425);
PAINT GREEN (375 4425);
DISPLAY INVISIBLE (375 4425);
FORCEPROP 1 LAST PATH I31
J 2
(700 4550);
DISPLAY 0.936170 (700 4550);
PAINT GREEN (700 4550);
DISPLAY INVISIBLE (700 4550);
FORCEADD TAP..6
R 2
(700 4950);
FORCEPROP 3 LASTPIN (650 4950) SIG_NAME M_M_DQS_DP<15>
J 0
(660 4960);
DISPLAY 0.659574 (660 4960);
PAINT MONO (660 4960);
DISPLAY INVISIBLE (660 4960);
FORCEPROP 1 LASTPIN (650 4950) BN 15
J 2
(700 4960);
DISPLAY 0.617021 (700 4960);
PAINT PINK (700 4960);
FORCEPROP 2 LAST CDS_LIB mstr_standard
J 0
(700 4950);
DISPLAY 0.787234 (700 4950);
PAINT MONO (700 4950);
DISPLAY INVISIBLE (700 4950);
FORCEPROP 1 LAST BODY_TYPE PLUMBING
J 2
(700 4900);
DISPLAY 1.234043 (700 4900);
PAINT GREEN (700 4900);
DISPLAY INVISIBLE (700 4900);
FORCEPROP 1 LAST HDL_TAP TRUE
J 2
(375 4825);
DISPLAY 1.234043 (375 4825);
PAINT GREEN (375 4825);
DISPLAY INVISIBLE (375 4825);
FORCEPROP 1 LAST PATH I32
J 2
(700 4950);
DISPLAY 0.936170 (700 4950);
PAINT GREEN (700 4950);
DISPLAY INVISIBLE (700 4950);
FORCEADD TAP..6
R 2
(700 4850);
FORCEPROP 3 LASTPIN (650 4850) SIG_NAME M_M_DQS_DP<14>
J 0
(660 4860);
DISPLAY 0.659574 (660 4860);
PAINT MONO (660 4860);
DISPLAY INVISIBLE (660 4860);
FORCEPROP 1 LASTPIN (650 4850) BN 14
J 2
(700 4860);
DISPLAY 0.617021 (700 4860);
PAINT PINK (700 4860);
FORCEPROP 2 LAST CDS_LIB mstr_standard
J 0
(700 4850);
DISPLAY 0.787234 (700 4850);
PAINT MONO (700 4850);
DISPLAY INVISIBLE (700 4850);
FORCEPROP 1 LAST BODY_TYPE PLUMBING
J 2
(700 4800);
DISPLAY 1.234043 (700 4800);
PAINT GREEN (700 4800);
DISPLAY INVISIBLE (700 4800);
FORCEPROP 1 LAST HDL_TAP TRUE
J 2
(375 4725);
DISPLAY 1.234043 (375 4725);
PAINT GREEN (375 4725);
DISPLAY INVISIBLE (375 4725);
FORCEPROP 1 LAST PATH I33
J 2
(700 4850);
DISPLAY 0.936170 (700 4850);
PAINT GREEN (700 4850);
DISPLAY INVISIBLE (700 4850);
FORCEADD OFFPAGE..3
(-1200 4950);
FORCEPROP 2 LAST $XR1 88 
J 0
(-896 4950);
DISPLAY 0.638298 (-896 4950);
PAINT MONO (-896 4950);
FORCEPROP 2 LAST $XR0 62 
J 0
(-986 4950);
DISPLAY 0.638298 (-986 4950);
PAINT MONO (-986 4950);
FORCEPROP 2 LAST CDS_LIB mstr_standard
J 0
(-1200 4950);
DISPLAY 0.787234 (-1200 4950);
PAINT MONO (-1200 4950);
DISPLAY INVISIBLE (-1200 4950);
FORCEPROP 1 LAST OFFPAGE TRUE
J 0
(-875 4825);
DISPLAY 0.936170 (-875 4825);
PAINT GREEN (-875 4825);
DISPLAY INVISIBLE (-875 4825);
FORCEPROP 1 LAST COMMENT_BODY TRUE
J 0
(-1250 4850);
DISPLAY 0.936170 (-1250 4850);
PAINT GREEN (-1250 4850);
DISPLAY INVISIBLE (-1250 4850);
FORCEPROP 2 LAST PATH I34
J 0
(-1000 5025);
DISPLAY 0.787234 (-1000 5025);
PAINT MONO (-1000 5025);
DISPLAY INVISIBLE (-1000 5025);
FORCEADD TAP..6
R 2
(-1750 4700);
FORCEPROP 3 LASTPIN (-1800 4700) SIG_NAME M_M_DQ<58>
J 0
(-1790 4710);
DISPLAY 0.659574 (-1790 4710);
PAINT MONO (-1790 4710);
DISPLAY INVISIBLE (-1790 4710);
FORCEPROP 1 LASTPIN (-1800 4700) BN 58
J 2
(-1750 4710);
DISPLAY 0.617021 (-1750 4710);
PAINT PINK (-1750 4710);
FORCEPROP 2 LAST CDS_LIB mstr_standard
J 2
(-1750 4700);
DISPLAY 0.787234 (-1750 4700);
PAINT MONO (-1750 4700);
DISPLAY INVISIBLE (-1750 4700);
FORCEPROP 1 LAST BODY_TYPE PLUMBING
J 2
(-1750 4650);
DISPLAY 1.234043 (-1750 4650);
PAINT GREEN (-1750 4650);
DISPLAY INVISIBLE (-1750 4650);
FORCEPROP 1 LAST HDL_TAP TRUE
J 2
(-2075 4575);
DISPLAY 1.234043 (-2075 4575);
PAINT GREEN (-2075 4575);
DISPLAY INVISIBLE (-2075 4575);
FORCEPROP 1 LAST PATH I35
J 2
(-1750 4700);
DISPLAY 0.936170 (-1750 4700);
PAINT GREEN (-1750 4700);
DISPLAY INVISIBLE (-1750 4700);
FORCEADD TAP..6
R 2
(-1750 4900);
FORCEPROP 3 LASTPIN (-1800 4900) SIG_NAME M_M_DQ<62>
J 0
(-1790 4910);
DISPLAY 0.659574 (-1790 4910);
PAINT MONO (-1790 4910);
DISPLAY INVISIBLE (-1790 4910);
FORCEPROP 1 LASTPIN (-1800 4900) BN 62
J 2
(-1750 4910);
DISPLAY 0.617021 (-1750 4910);
PAINT PINK (-1750 4910);
FORCEPROP 2 LAST CDS_LIB mstr_standard
J 2
(-1750 4900);
DISPLAY 0.787234 (-1750 4900);
PAINT MONO (-1750 4900);
DISPLAY INVISIBLE (-1750 4900);
FORCEPROP 1 LAST BODY_TYPE PLUMBING
J 2
(-1750 4850);
DISPLAY 1.234043 (-1750 4850);
PAINT GREEN (-1750 4850);
DISPLAY INVISIBLE (-1750 4850);
FORCEPROP 1 LAST HDL_TAP TRUE
J 2
(-2075 4775);
DISPLAY 1.234043 (-2075 4775);
PAINT GREEN (-2075 4775);
DISPLAY INVISIBLE (-2075 4775);
FORCEPROP 1 LAST PATH I36
J 2
(-1750 4900);
DISPLAY 0.936170 (-1750 4900);
PAINT GREEN (-1750 4900);
DISPLAY INVISIBLE (-1750 4900);
FORCEADD TAP..6
R 2
(-1750 4850);
FORCEPROP 3 LASTPIN (-1800 4850) SIG_NAME M_M_DQ<63>
J 0
(-1790 4860);
DISPLAY 0.659574 (-1790 4860);
PAINT MONO (-1790 4860);
DISPLAY INVISIBLE (-1790 4860);
FORCEPROP 1 LASTPIN (-1800 4850) BN 63
J 2
(-1750 4860);
DISPLAY 0.617021 (-1750 4860);
PAINT PINK (-1750 4860);
FORCEPROP 2 LAST CDS_LIB mstr_standard
J 2
(-1750 4850);
DISPLAY 0.787234 (-1750 4850);
PAINT MONO (-1750 4850);
DISPLAY INVISIBLE (-1750 4850);
FORCEPROP 1 LAST BODY_TYPE PLUMBING
J 2
(-1750 4800);
DISPLAY 1.234043 (-1750 4800);
PAINT GREEN (-1750 4800);
DISPLAY INVISIBLE (-1750 4800);
FORCEPROP 1 LAST HDL_TAP TRUE
J 2
(-2075 4725);
DISPLAY 1.234043 (-2075 4725);
PAINT GREEN (-2075 4725);
DISPLAY INVISIBLE (-2075 4725);
FORCEPROP 1 LAST PATH I37
J 2
(-1750 4850);
DISPLAY 0.936170 (-1750 4850);
PAINT GREEN (-1750 4850);
DISPLAY INVISIBLE (-1750 4850);
FORCEADD TAP..6
R 2
(-1750 4800);
FORCEPROP 3 LASTPIN (-1800 4800) SIG_NAME M_M_DQ<60>
J 0
(-1790 4810);
DISPLAY 0.659574 (-1790 4810);
PAINT MONO (-1790 4810);
DISPLAY INVISIBLE (-1790 4810);
FORCEPROP 1 LASTPIN (-1800 4800) BN 60
J 2
(-1750 4810);
DISPLAY 0.617021 (-1750 4810);
PAINT PINK (-1750 4810);
FORCEPROP 2 LAST CDS_LIB mstr_standard
J 2
(-1750 4800);
DISPLAY 0.787234 (-1750 4800);
PAINT MONO (-1750 4800);
DISPLAY INVISIBLE (-1750 4800);
FORCEPROP 1 LAST BODY_TYPE PLUMBING
J 2
(-1750 4750);
DISPLAY 1.234043 (-1750 4750);
PAINT GREEN (-1750 4750);
DISPLAY INVISIBLE (-1750 4750);
FORCEPROP 1 LAST HDL_TAP TRUE
J 2
(-2075 4675);
DISPLAY 1.234043 (-2075 4675);
PAINT GREEN (-2075 4675);
DISPLAY INVISIBLE (-2075 4675);
FORCEPROP 1 LAST PATH I38
J 2
(-1750 4800);
DISPLAY 0.936170 (-1750 4800);
PAINT GREEN (-1750 4800);
DISPLAY INVISIBLE (-1750 4800);
FORCEADD TAP..6
R 2
(-1750 4750);
FORCEPROP 3 LASTPIN (-1800 4750) SIG_NAME M_M_DQ<61>
J 0
(-1790 4760);
DISPLAY 0.659574 (-1790 4760);
PAINT MONO (-1790 4760);
DISPLAY INVISIBLE (-1790 4760);
FORCEPROP 1 LASTPIN (-1800 4750) BN 61
J 2
(-1750 4760);
DISPLAY 0.617021 (-1750 4760);
PAINT PINK (-1750 4760);
FORCEPROP 2 LAST CDS_LIB mstr_standard
J 2
(-1750 4750);
DISPLAY 0.787234 (-1750 4750);
PAINT MONO (-1750 4750);
DISPLAY INVISIBLE (-1750 4750);
FORCEPROP 1 LAST BODY_TYPE PLUMBING
J 2
(-1750 4700);
DISPLAY 1.234043 (-1750 4700);
PAINT GREEN (-1750 4700);
DISPLAY INVISIBLE (-1750 4700);
FORCEPROP 1 LAST HDL_TAP TRUE
J 2
(-2075 4625);
DISPLAY 1.234043 (-2075 4625);
PAINT GREEN (-2075 4625);
DISPLAY INVISIBLE (-2075 4625);
FORCEPROP 1 LAST PATH I39
J 2
(-1750 4750);
DISPLAY 0.936170 (-1750 4750);
PAINT GREEN (-1750 4750);
DISPLAY INVISIBLE (-1750 4750);
FORCEADD TAP..6
R 2
(900 5000);
FORCEPROP 3 LASTPIN (850 5000) SIG_NAME M_M_DQS_DN<16>
J 0
(860 5010);
DISPLAY 0.659574 (860 5010);
PAINT MONO (860 5010);
DISPLAY INVISIBLE (860 5010);
FORCEPROP 1 LASTPIN (850 5000) BN 16
J 2
(900 5010);
DISPLAY 0.617021 (900 5010);
PAINT PINK (900 5010);
FORCEPROP 2 LAST CDS_LIB mstr_standard
J 0
(900 5000);
DISPLAY 0.787234 (900 5000);
PAINT MONO (900 5000);
DISPLAY INVISIBLE (900 5000);
FORCEPROP 1 LAST BODY_TYPE PLUMBING
J 2
(900 4950);
DISPLAY 1.234043 (900 4950);
PAINT GREEN (900 4950);
DISPLAY INVISIBLE (900 4950);
FORCEPROP 1 LAST HDL_TAP TRUE
J 2
(575 4875);
DISPLAY 1.234043 (575 4875);
PAINT GREEN (575 4875);
DISPLAY INVISIBLE (575 4875);
FORCEPROP 1 LAST PATH I4
J 2
(900 5000);
DISPLAY 0.936170 (900 5000);
PAINT GREEN (900 5000);
DISPLAY INVISIBLE (900 5000);
FORCEADD TAP..6
R 2
(-1750 4450);
FORCEPROP 3 LASTPIN (-1800 4450) SIG_NAME M_M_DQ<55>
J 0
(-1790 4460);
DISPLAY 0.659574 (-1790 4460);
PAINT MONO (-1790 4460);
DISPLAY INVISIBLE (-1790 4460);
FORCEPROP 1 LASTPIN (-1800 4450) BN 55
J 2
(-1750 4460);
DISPLAY 0.617021 (-1750 4460);
PAINT PINK (-1750 4460);
FORCEPROP 2 LAST CDS_LIB mstr_standard
J 2
(-1750 4450);
DISPLAY 0.787234 (-1750 4450);
PAINT MONO (-1750 4450);
DISPLAY INVISIBLE (-1750 4450);
FORCEPROP 1 LAST BODY_TYPE PLUMBING
J 2
(-1750 4400);
DISPLAY 1.234043 (-1750 4400);
PAINT GREEN (-1750 4400);
DISPLAY INVISIBLE (-1750 4400);
FORCEPROP 1 LAST HDL_TAP TRUE
J 2
(-2075 4325);
DISPLAY 1.234043 (-2075 4325);
PAINT GREEN (-2075 4325);
DISPLAY INVISIBLE (-2075 4325);
FORCEPROP 1 LAST PATH I40
J 2
(-1750 4450);
DISPLAY 0.936170 (-1750 4450);
PAINT GREEN (-1750 4450);
DISPLAY INVISIBLE (-1750 4450);
FORCEADD TAP..6
R 2
(-1750 4600);
FORCEPROP 3 LASTPIN (-1800 4600) SIG_NAME M_M_DQ<56>
J 0
(-1790 4610);
DISPLAY 0.659574 (-1790 4610);
PAINT MONO (-1790 4610);
DISPLAY INVISIBLE (-1790 4610);
FORCEPROP 1 LASTPIN (-1800 4600) BN 56
J 2
(-1750 4610);
DISPLAY 0.617021 (-1750 4610);
PAINT PINK (-1750 4610);
FORCEPROP 2 LAST CDS_LIB mstr_standard
J 2
(-1750 4600);
DISPLAY 0.787234 (-1750 4600);
PAINT MONO (-1750 4600);
DISPLAY INVISIBLE (-1750 4600);
FORCEPROP 1 LAST BODY_TYPE PLUMBING
J 2
(-1750 4550);
DISPLAY 1.234043 (-1750 4550);
PAINT GREEN (-1750 4550);
DISPLAY INVISIBLE (-1750 4550);
FORCEPROP 1 LAST HDL_TAP TRUE
J 2
(-2075 4475);
DISPLAY 1.234043 (-2075 4475);
PAINT GREEN (-2075 4475);
DISPLAY INVISIBLE (-2075 4475);
FORCEPROP 1 LAST PATH I41
J 2
(-1750 4600);
DISPLAY 0.936170 (-1750 4600);
PAINT GREEN (-1750 4600);
DISPLAY INVISIBLE (-1750 4600);
FORCEADD TAP..6
R 2
(-1750 4650);
FORCEPROP 3 LASTPIN (-1800 4650) SIG_NAME M_M_DQ<59>
J 0
(-1790 4660);
DISPLAY 0.659574 (-1790 4660);
PAINT MONO (-1790 4660);
DISPLAY INVISIBLE (-1790 4660);
FORCEPROP 1 LASTPIN (-1800 4650) BN 59
J 2
(-1750 4660);
DISPLAY 0.617021 (-1750 4660);
PAINT PINK (-1750 4660);
FORCEPROP 2 LAST CDS_LIB mstr_standard
J 2
(-1750 4650);
DISPLAY 0.787234 (-1750 4650);
PAINT MONO (-1750 4650);
DISPLAY INVISIBLE (-1750 4650);
FORCEPROP 1 LAST BODY_TYPE PLUMBING
J 2
(-1750 4600);
DISPLAY 1.234043 (-1750 4600);
PAINT GREEN (-1750 4600);
DISPLAY INVISIBLE (-1750 4600);
FORCEPROP 1 LAST HDL_TAP TRUE
J 2
(-2075 4525);
DISPLAY 1.234043 (-2075 4525);
PAINT GREEN (-2075 4525);
DISPLAY INVISIBLE (-2075 4525);
FORCEPROP 1 LAST PATH I42
J 2
(-1750 4650);
DISPLAY 0.936170 (-1750 4650);
PAINT GREEN (-1750 4650);
DISPLAY INVISIBLE (-1750 4650);
FORCEADD TAP..6
R 2
(-1750 4500);
FORCEPROP 3 LASTPIN (-1800 4500) SIG_NAME M_M_DQ<54>
J 0
(-1790 4510);
DISPLAY 0.659574 (-1790 4510);
PAINT MONO (-1790 4510);
DISPLAY INVISIBLE (-1790 4510);
FORCEPROP 1 LASTPIN (-1800 4500) BN 54
J 2
(-1750 4510);
DISPLAY 0.617021 (-1750 4510);
PAINT PINK (-1750 4510);
FORCEPROP 2 LAST CDS_LIB mstr_standard
J 2
(-1750 4500);
DISPLAY 0.787234 (-1750 4500);
PAINT MONO (-1750 4500);
DISPLAY INVISIBLE (-1750 4500);
FORCEPROP 1 LAST BODY_TYPE PLUMBING
J 2
(-1750 4450);
DISPLAY 1.234043 (-1750 4450);
PAINT GREEN (-1750 4450);
DISPLAY INVISIBLE (-1750 4450);
FORCEPROP 1 LAST HDL_TAP TRUE
J 2
(-2075 4375);
DISPLAY 1.234043 (-2075 4375);
PAINT GREEN (-2075 4375);
DISPLAY INVISIBLE (-2075 4375);
FORCEPROP 1 LAST PATH I43
J 2
(-1750 4500);
DISPLAY 0.936170 (-1750 4500);
PAINT GREEN (-1750 4500);
DISPLAY INVISIBLE (-1750 4500);
FORCEADD TAP..6
R 2
(-1750 4550);
FORCEPROP 3 LASTPIN (-1800 4550) SIG_NAME M_M_DQ<57>
J 0
(-1790 4560);
DISPLAY 0.659574 (-1790 4560);
PAINT MONO (-1790 4560);
DISPLAY INVISIBLE (-1790 4560);
FORCEPROP 1 LASTPIN (-1800 4550) BN 57
J 2
(-1750 4560);
DISPLAY 0.617021 (-1750 4560);
PAINT PINK (-1750 4560);
FORCEPROP 2 LAST CDS_LIB mstr_standard
J 2
(-1750 4550);
DISPLAY 0.787234 (-1750 4550);
PAINT MONO (-1750 4550);
DISPLAY INVISIBLE (-1750 4550);
FORCEPROP 1 LAST BODY_TYPE PLUMBING
J 2
(-1750 4500);
DISPLAY 1.234043 (-1750 4500);
PAINT GREEN (-1750 4500);
DISPLAY INVISIBLE (-1750 4500);
FORCEPROP 1 LAST HDL_TAP TRUE
J 2
(-2075 4425);
DISPLAY 1.234043 (-2075 4425);
PAINT GREEN (-2075 4425);
DISPLAY INVISIBLE (-2075 4425);
FORCEPROP 1 LAST PATH I44
J 2
(-1750 4550);
DISPLAY 0.936170 (-1750 4550);
PAINT GREEN (-1750 4550);
DISPLAY INVISIBLE (-1750 4550);
FORCEADD TAP..6
R 2
(-1750 4200);
FORCEPROP 3 LASTPIN (-1800 4200) SIG_NAME M_M_DQ<48>
J 0
(-1790 4210);
DISPLAY 0.659574 (-1790 4210);
PAINT MONO (-1790 4210);
DISPLAY INVISIBLE (-1790 4210);
FORCEPROP 1 LASTPIN (-1800 4200) BN 48
J 2
(-1750 4210);
DISPLAY 0.617021 (-1750 4210);
PAINT PINK (-1750 4210);
FORCEPROP 2 LAST CDS_LIB mstr_standard
J 2
(-1750 4200);
DISPLAY 0.787234 (-1750 4200);
PAINT MONO (-1750 4200);
DISPLAY INVISIBLE (-1750 4200);
FORCEPROP 1 LAST BODY_TYPE PLUMBING
J 2
(-1750 4150);
DISPLAY 1.234043 (-1750 4150);
PAINT GREEN (-1750 4150);
DISPLAY INVISIBLE (-1750 4150);
FORCEPROP 1 LAST HDL_TAP TRUE
J 2
(-2075 4075);
DISPLAY 1.234043 (-2075 4075);
PAINT GREEN (-2075 4075);
DISPLAY INVISIBLE (-2075 4075);
FORCEPROP 1 LAST PATH I45
J 2
(-1750 4200);
DISPLAY 0.936170 (-1750 4200);
PAINT GREEN (-1750 4200);
DISPLAY INVISIBLE (-1750 4200);
FORCEADD TAP..6
R 2
(-1750 4400);
FORCEPROP 3 LASTPIN (-1800 4400) SIG_NAME M_M_DQ<52>
J 0
(-1790 4410);
DISPLAY 0.659574 (-1790 4410);
PAINT MONO (-1790 4410);
DISPLAY INVISIBLE (-1790 4410);
FORCEPROP 1 LASTPIN (-1800 4400) BN 52
J 2
(-1750 4410);
DISPLAY 0.617021 (-1750 4410);
PAINT PINK (-1750 4410);
FORCEPROP 2 LAST CDS_LIB mstr_standard
J 2
(-1750 4400);
DISPLAY 0.787234 (-1750 4400);
PAINT MONO (-1750 4400);
DISPLAY INVISIBLE (-1750 4400);
FORCEPROP 1 LAST BODY_TYPE PLUMBING
J 2
(-1750 4350);
DISPLAY 1.234043 (-1750 4350);
PAINT GREEN (-1750 4350);
DISPLAY INVISIBLE (-1750 4350);
FORCEPROP 1 LAST HDL_TAP TRUE
J 2
(-2075 4275);
DISPLAY 1.234043 (-2075 4275);
PAINT GREEN (-2075 4275);
DISPLAY INVISIBLE (-2075 4275);
FORCEPROP 1 LAST PATH I46
J 2
(-1750 4400);
DISPLAY 0.936170 (-1750 4400);
PAINT GREEN (-1750 4400);
DISPLAY INVISIBLE (-1750 4400);
FORCEADD TAP..6
R 2
(-1750 4350);
FORCEPROP 3 LASTPIN (-1800 4350) SIG_NAME M_M_DQ<53>
J 0
(-1790 4360);
DISPLAY 0.659574 (-1790 4360);
PAINT MONO (-1790 4360);
DISPLAY INVISIBLE (-1790 4360);
FORCEPROP 1 LASTPIN (-1800 4350) BN 53
J 2
(-1750 4360);
DISPLAY 0.617021 (-1750 4360);
PAINT PINK (-1750 4360);
FORCEPROP 2 LAST CDS_LIB mstr_standard
J 2
(-1750 4350);
DISPLAY 0.787234 (-1750 4350);
PAINT MONO (-1750 4350);
DISPLAY INVISIBLE (-1750 4350);
FORCEPROP 1 LAST BODY_TYPE PLUMBING
J 2
(-1750 4300);
DISPLAY 1.234043 (-1750 4300);
PAINT GREEN (-1750 4300);
DISPLAY INVISIBLE (-1750 4300);
FORCEPROP 1 LAST HDL_TAP TRUE
J 2
(-2075 4225);
DISPLAY 1.234043 (-2075 4225);
PAINT GREEN (-2075 4225);
DISPLAY INVISIBLE (-2075 4225);
FORCEPROP 1 LAST PATH I47
J 2
(-1750 4350);
DISPLAY 0.936170 (-1750 4350);
PAINT GREEN (-1750 4350);
DISPLAY INVISIBLE (-1750 4350);
FORCEADD TAP..6
R 2
(-1750 4250);
FORCEPROP 3 LASTPIN (-1800 4250) SIG_NAME M_M_DQ<51>
J 0
(-1790 4260);
DISPLAY 0.659574 (-1790 4260);
PAINT MONO (-1790 4260);
DISPLAY INVISIBLE (-1790 4260);
FORCEPROP 1 LASTPIN (-1800 4250) BN 51
J 2
(-1750 4260);
DISPLAY 0.617021 (-1750 4260);
PAINT PINK (-1750 4260);
FORCEPROP 2 LAST CDS_LIB mstr_standard
J 2
(-1750 4250);
DISPLAY 0.787234 (-1750 4250);
PAINT MONO (-1750 4250);
DISPLAY INVISIBLE (-1750 4250);
FORCEPROP 1 LAST BODY_TYPE PLUMBING
J 2
(-1750 4200);
DISPLAY 1.234043 (-1750 4200);
PAINT GREEN (-1750 4200);
DISPLAY INVISIBLE (-1750 4200);
FORCEPROP 1 LAST HDL_TAP TRUE
J 2
(-2075 4125);
DISPLAY 1.234043 (-2075 4125);
PAINT GREEN (-2075 4125);
DISPLAY INVISIBLE (-2075 4125);
FORCEPROP 1 LAST PATH I48
J 2
(-1750 4250);
DISPLAY 0.936170 (-1750 4250);
PAINT GREEN (-1750 4250);
DISPLAY INVISIBLE (-1750 4250);
FORCEADD TAP..6
R 2
(-1750 4300);
FORCEPROP 3 LASTPIN (-1800 4300) SIG_NAME M_M_DQ<50>
J 0
(-1790 4310);
DISPLAY 0.659574 (-1790 4310);
PAINT MONO (-1790 4310);
DISPLAY INVISIBLE (-1790 4310);
FORCEPROP 1 LASTPIN (-1800 4300) BN 50
J 2
(-1750 4310);
DISPLAY 0.617021 (-1750 4310);
PAINT PINK (-1750 4310);
FORCEPROP 2 LAST CDS_LIB mstr_standard
J 2
(-1750 4300);
DISPLAY 0.787234 (-1750 4300);
PAINT MONO (-1750 4300);
DISPLAY INVISIBLE (-1750 4300);
FORCEPROP 1 LAST BODY_TYPE PLUMBING
J 2
(-1750 4250);
DISPLAY 1.234043 (-1750 4250);
PAINT GREEN (-1750 4250);
DISPLAY INVISIBLE (-1750 4250);
FORCEPROP 1 LAST HDL_TAP TRUE
J 2
(-2075 4175);
DISPLAY 1.234043 (-2075 4175);
PAINT GREEN (-2075 4175);
DISPLAY INVISIBLE (-2075 4175);
FORCEPROP 1 LAST PATH I49
J 2
(-1750 4300);
DISPLAY 0.936170 (-1750 4300);
PAINT GREEN (-1750 4300);
DISPLAY INVISIBLE (-1750 4300);
FORCEADD TAP..6
R 2
(900 4900);
FORCEPROP 3 LASTPIN (850 4900) SIG_NAME M_M_DQS_DN<15>
J 0
(860 4910);
DISPLAY 0.659574 (860 4910);
PAINT MONO (860 4910);
DISPLAY INVISIBLE (860 4910);
FORCEPROP 1 LASTPIN (850 4900) BN 15
J 2
(900 4910);
DISPLAY 0.617021 (900 4910);
PAINT PINK (900 4910);
FORCEPROP 2 LAST CDS_LIB mstr_standard
J 0
(900 4900);
DISPLAY 0.787234 (900 4900);
PAINT MONO (900 4900);
DISPLAY INVISIBLE (900 4900);
FORCEPROP 1 LAST BODY_TYPE PLUMBING
J 2
(900 4850);
DISPLAY 1.234043 (900 4850);
PAINT GREEN (900 4850);
DISPLAY INVISIBLE (900 4850);
FORCEPROP 1 LAST HDL_TAP TRUE
J 2
(575 4775);
DISPLAY 1.234043 (575 4775);
PAINT GREEN (575 4775);
DISPLAY INVISIBLE (575 4775);
FORCEPROP 1 LAST PATH I5
J 2
(900 4900);
DISPLAY 0.936170 (900 4900);
PAINT GREEN (900 4900);
DISPLAY INVISIBLE (900 4900);
FORCEADD TAP..6
R 2
(-1750 4100);
FORCEPROP 3 LASTPIN (-1800 4100) SIG_NAME M_M_DQ<46>
J 0
(-1790 4110);
DISPLAY 0.659574 (-1790 4110);
PAINT MONO (-1790 4110);
DISPLAY INVISIBLE (-1790 4110);
FORCEPROP 1 LASTPIN (-1800 4100) BN 46
J 2
(-1750 4110);
DISPLAY 0.617021 (-1750 4110);
PAINT PINK (-1750 4110);
FORCEPROP 2 LAST CDS_LIB mstr_standard
J 2
(-1750 4100);
DISPLAY 0.787234 (-1750 4100);
PAINT MONO (-1750 4100);
DISPLAY INVISIBLE (-1750 4100);
FORCEPROP 1 LAST BODY_TYPE PLUMBING
J 2
(-1750 4050);
DISPLAY 1.234043 (-1750 4050);
PAINT GREEN (-1750 4050);
DISPLAY INVISIBLE (-1750 4050);
FORCEPROP 1 LAST HDL_TAP TRUE
J 2
(-2075 3975);
DISPLAY 1.234043 (-2075 3975);
PAINT GREEN (-2075 3975);
DISPLAY INVISIBLE (-2075 3975);
FORCEPROP 1 LAST PATH I50
J 2
(-1750 4100);
DISPLAY 0.936170 (-1750 4100);
PAINT GREEN (-1750 4100);
DISPLAY INVISIBLE (-1750 4100);
FORCEADD TAP..6
R 2
(-1750 4150);
FORCEPROP 3 LASTPIN (-1800 4150) SIG_NAME M_M_DQ<49>
J 0
(-1790 4160);
DISPLAY 0.659574 (-1790 4160);
PAINT MONO (-1790 4160);
DISPLAY INVISIBLE (-1790 4160);
FORCEPROP 1 LASTPIN (-1800 4150) BN 49
J 2
(-1750 4160);
DISPLAY 0.617021 (-1750 4160);
PAINT PINK (-1750 4160);
FORCEPROP 2 LAST CDS_LIB mstr_standard
J 2
(-1750 4150);
DISPLAY 0.787234 (-1750 4150);
PAINT MONO (-1750 4150);
DISPLAY INVISIBLE (-1750 4150);
FORCEPROP 1 LAST BODY_TYPE PLUMBING
J 2
(-1750 4100);
DISPLAY 1.234043 (-1750 4100);
PAINT GREEN (-1750 4100);
DISPLAY INVISIBLE (-1750 4100);
FORCEPROP 1 LAST HDL_TAP TRUE
J 2
(-2075 4025);
DISPLAY 1.234043 (-2075 4025);
PAINT GREEN (-2075 4025);
DISPLAY INVISIBLE (-2075 4025);
FORCEPROP 1 LAST PATH I51
J 2
(-1750 4150);
DISPLAY 0.936170 (-1750 4150);
PAINT GREEN (-1750 4150);
DISPLAY INVISIBLE (-1750 4150);
FORCEADD TAP..6
R 2
(-1750 4050);
FORCEPROP 3 LASTPIN (-1800 4050) SIG_NAME M_M_DQ<47>
J 0
(-1790 4060);
DISPLAY 0.659574 (-1790 4060);
PAINT MONO (-1790 4060);
DISPLAY INVISIBLE (-1790 4060);
FORCEPROP 1 LASTPIN (-1800 4050) BN 47
J 2
(-1750 4060);
DISPLAY 0.617021 (-1750 4060);
PAINT PINK (-1750 4060);
FORCEPROP 2 LAST CDS_LIB mstr_standard
J 2
(-1750 4050);
DISPLAY 0.787234 (-1750 4050);
PAINT MONO (-1750 4050);
DISPLAY INVISIBLE (-1750 4050);
FORCEPROP 1 LAST BODY_TYPE PLUMBING
J 2
(-1750 4000);
DISPLAY 1.234043 (-1750 4000);
PAINT GREEN (-1750 4000);
DISPLAY INVISIBLE (-1750 4000);
FORCEPROP 1 LAST HDL_TAP TRUE
J 2
(-2075 3925);
DISPLAY 1.234043 (-2075 3925);
PAINT GREEN (-2075 3925);
DISPLAY INVISIBLE (-2075 3925);
FORCEPROP 1 LAST PATH I52
J 2
(-1750 4050);
DISPLAY 0.936170 (-1750 4050);
PAINT GREEN (-1750 4050);
DISPLAY INVISIBLE (-1750 4050);
FORCEADD TAP..6
R 2
(-1750 3950);
FORCEPROP 3 LASTPIN (-1800 3950) SIG_NAME M_M_DQ<45>
J 0
(-1790 3960);
DISPLAY 0.659574 (-1790 3960);
PAINT MONO (-1790 3960);
DISPLAY INVISIBLE (-1790 3960);
FORCEPROP 1 LASTPIN (-1800 3950) BN 45
J 2
(-1750 3960);
DISPLAY 0.617021 (-1750 3960);
PAINT PINK (-1750 3960);
FORCEPROP 2 LAST CDS_LIB mstr_standard
J 2
(-1750 3950);
DISPLAY 0.787234 (-1750 3950);
PAINT MONO (-1750 3950);
DISPLAY INVISIBLE (-1750 3950);
FORCEPROP 1 LAST BODY_TYPE PLUMBING
J 2
(-1750 3900);
DISPLAY 1.234043 (-1750 3900);
PAINT GREEN (-1750 3900);
DISPLAY INVISIBLE (-1750 3900);
FORCEPROP 1 LAST HDL_TAP TRUE
J 2
(-2075 3825);
DISPLAY 1.234043 (-2075 3825);
PAINT GREEN (-2075 3825);
DISPLAY INVISIBLE (-2075 3825);
FORCEPROP 1 LAST PATH I53
J 2
(-1750 3950);
DISPLAY 0.936170 (-1750 3950);
PAINT GREEN (-1750 3950);
DISPLAY INVISIBLE (-1750 3950);
FORCEADD TAP..6
R 2
(-1750 4000);
FORCEPROP 3 LASTPIN (-1800 4000) SIG_NAME M_M_DQ<44>
J 0
(-1790 4010);
DISPLAY 0.659574 (-1790 4010);
PAINT MONO (-1790 4010);
DISPLAY INVISIBLE (-1790 4010);
FORCEPROP 1 LASTPIN (-1800 4000) BN 44
J 2
(-1750 4010);
DISPLAY 0.617021 (-1750 4010);
PAINT PINK (-1750 4010);
FORCEPROP 2 LAST CDS_LIB mstr_standard
J 2
(-1750 4000);
DISPLAY 0.787234 (-1750 4000);
PAINT MONO (-1750 4000);
DISPLAY INVISIBLE (-1750 4000);
FORCEPROP 1 LAST BODY_TYPE PLUMBING
J 2
(-1750 3950);
DISPLAY 1.234043 (-1750 3950);
PAINT GREEN (-1750 3950);
DISPLAY INVISIBLE (-1750 3950);
FORCEPROP 1 LAST HDL_TAP TRUE
J 2
(-2075 3875);
DISPLAY 1.234043 (-2075 3875);
PAINT GREEN (-2075 3875);
DISPLAY INVISIBLE (-2075 3875);
FORCEPROP 1 LAST PATH I54
J 2
(-1750 4000);
DISPLAY 0.936170 (-1750 4000);
PAINT GREEN (-1750 4000);
DISPLAY INVISIBLE (-1750 4000);
FORCEADD TAP..6
R 2
(700 4250);
FORCEPROP 3 LASTPIN (650 4250) SIG_NAME M_M_DQS_DP<8>
J 0
(660 4260);
DISPLAY 0.659574 (660 4260);
PAINT MONO (660 4260);
DISPLAY INVISIBLE (660 4260);
FORCEPROP 1 LASTPIN (650 4250) BN 8
J 2
(700 4260);
DISPLAY 0.617021 (700 4260);
PAINT PINK (700 4260);
FORCEPROP 2 LAST CDS_LIB mstr_standard
J 0
(700 4250);
DISPLAY 0.787234 (700 4250);
PAINT MONO (700 4250);
DISPLAY INVISIBLE (700 4250);
FORCEPROP 1 LAST BODY_TYPE PLUMBING
J 2
(700 4200);
DISPLAY 1.234043 (700 4200);
PAINT GREEN (700 4200);
DISPLAY INVISIBLE (700 4200);
FORCEPROP 1 LAST HDL_TAP TRUE
J 2
(375 4125);
DISPLAY 1.234043 (375 4125);
PAINT GREEN (375 4125);
DISPLAY INVISIBLE (375 4125);
FORCEPROP 1 LAST PATH I55
J 2
(700 4250);
DISPLAY 0.936170 (700 4250);
PAINT GREEN (700 4250);
DISPLAY INVISIBLE (700 4250);
FORCEADD TAP..6
R 2
(700 4150);
FORCEPROP 3 LASTPIN (650 4150) SIG_NAME M_M_DQS_DP<7>
J 0
(660 4160);
DISPLAY 0.659574 (660 4160);
PAINT MONO (660 4160);
DISPLAY INVISIBLE (660 4160);
FORCEPROP 1 LASTPIN (650 4150) BN 7
J 2
(700 4160);
DISPLAY 0.617021 (700 4160);
PAINT PINK (700 4160);
FORCEPROP 2 LAST CDS_LIB mstr_standard
J 0
(700 4150);
DISPLAY 0.787234 (700 4150);
PAINT MONO (700 4150);
DISPLAY INVISIBLE (700 4150);
FORCEPROP 1 LAST BODY_TYPE PLUMBING
J 2
(700 4100);
DISPLAY 1.234043 (700 4100);
PAINT GREEN (700 4100);
DISPLAY INVISIBLE (700 4100);
FORCEPROP 1 LAST HDL_TAP TRUE
J 2
(375 4025);
DISPLAY 1.234043 (375 4025);
PAINT GREEN (375 4025);
DISPLAY INVISIBLE (375 4025);
FORCEPROP 1 LAST PATH I56
J 2
(700 4150);
DISPLAY 0.936170 (700 4150);
PAINT GREEN (700 4150);
DISPLAY INVISIBLE (700 4150);
FORCEADD TAP..6
R 2
(700 4050);
FORCEPROP 3 LASTPIN (650 4050) SIG_NAME M_M_DQS_DP<6>
J 0
(660 4060);
DISPLAY 0.659574 (660 4060);
PAINT MONO (660 4060);
DISPLAY INVISIBLE (660 4060);
FORCEPROP 1 LASTPIN (650 4050) BN 6
J 2
(700 4060);
DISPLAY 0.617021 (700 4060);
PAINT PINK (700 4060);
FORCEPROP 2 LAST CDS_LIB mstr_standard
J 0
(700 4050);
DISPLAY 0.787234 (700 4050);
PAINT MONO (700 4050);
DISPLAY INVISIBLE (700 4050);
FORCEPROP 1 LAST BODY_TYPE PLUMBING
J 2
(700 4000);
DISPLAY 1.234043 (700 4000);
PAINT GREEN (700 4000);
DISPLAY INVISIBLE (700 4000);
FORCEPROP 1 LAST HDL_TAP TRUE
J 2
(375 3925);
DISPLAY 1.234043 (375 3925);
PAINT GREEN (375 3925);
DISPLAY INVISIBLE (375 3925);
FORCEPROP 1 LAST PATH I57
J 2
(700 4050);
DISPLAY 0.936170 (700 4050);
PAINT GREEN (700 4050);
DISPLAY INVISIBLE (700 4050);
FORCEADD TAP..6
R 2
(700 4350);
FORCEPROP 3 LASTPIN (650 4350) SIG_NAME M_M_DQS_DP<9>
J 0
(660 4360);
DISPLAY 0.659574 (660 4360);
PAINT MONO (660 4360);
DISPLAY INVISIBLE (660 4360);
FORCEPROP 1 LASTPIN (650 4350) BN 9
J 2
(700 4360);
DISPLAY 0.617021 (700 4360);
PAINT PINK (700 4360);
FORCEPROP 2 LAST CDS_LIB mstr_standard
J 0
(700 4350);
DISPLAY 0.787234 (700 4350);
PAINT MONO (700 4350);
DISPLAY INVISIBLE (700 4350);
FORCEPROP 1 LAST BODY_TYPE PLUMBING
J 2
(700 4300);
DISPLAY 1.234043 (700 4300);
PAINT GREEN (700 4300);
DISPLAY INVISIBLE (700 4300);
FORCEPROP 1 LAST HDL_TAP TRUE
J 2
(375 4225);
DISPLAY 1.234043 (375 4225);
PAINT GREEN (375 4225);
DISPLAY INVISIBLE (375 4225);
FORCEPROP 1 LAST PATH I58
J 2
(700 4350);
DISPLAY 0.936170 (700 4350);
PAINT GREEN (700 4350);
DISPLAY INVISIBLE (700 4350);
FORCEADD TAP..6
R 2
(700 4450);
FORCEPROP 3 LASTPIN (650 4450) SIG_NAME M_M_DQS_DP<10>
J 0
(660 4460);
DISPLAY 0.659574 (660 4460);
PAINT MONO (660 4460);
DISPLAY INVISIBLE (660 4460);
FORCEPROP 1 LASTPIN (650 4450) BN 10
J 2
(700 4460);
DISPLAY 0.617021 (700 4460);
PAINT PINK (700 4460);
FORCEPROP 2 LAST CDS_LIB mstr_standard
J 0
(700 4450);
DISPLAY 0.787234 (700 4450);
PAINT MONO (700 4450);
DISPLAY INVISIBLE (700 4450);
FORCEPROP 1 LAST BODY_TYPE PLUMBING
J 2
(700 4400);
DISPLAY 1.234043 (700 4400);
PAINT GREEN (700 4400);
DISPLAY INVISIBLE (700 4400);
FORCEPROP 1 LAST HDL_TAP TRUE
J 2
(375 4325);
DISPLAY 1.234043 (375 4325);
PAINT GREEN (375 4325);
DISPLAY INVISIBLE (375 4325);
FORCEPROP 1 LAST PATH I59
J 2
(700 4450);
DISPLAY 0.936170 (700 4450);
PAINT GREEN (700 4450);
DISPLAY INVISIBLE (700 4450);
FORCEADD TAP..6
R 2
(900 4800);
FORCEPROP 3 LASTPIN (850 4800) SIG_NAME M_M_DQS_DN<14>
J 0
(860 4810);
DISPLAY 0.659574 (860 4810);
PAINT MONO (860 4810);
DISPLAY INVISIBLE (860 4810);
FORCEPROP 1 LASTPIN (850 4800) BN 14
J 2
(900 4810);
DISPLAY 0.617021 (900 4810);
PAINT PINK (900 4810);
FORCEPROP 2 LAST CDS_LIB mstr_standard
J 0
(900 4800);
DISPLAY 0.787234 (900 4800);
PAINT MONO (900 4800);
DISPLAY INVISIBLE (900 4800);
FORCEPROP 1 LAST BODY_TYPE PLUMBING
J 2
(900 4750);
DISPLAY 1.234043 (900 4750);
PAINT GREEN (900 4750);
DISPLAY INVISIBLE (900 4750);
FORCEPROP 1 LAST HDL_TAP TRUE
J 2
(575 4675);
DISPLAY 1.234043 (575 4675);
PAINT GREEN (575 4675);
DISPLAY INVISIBLE (575 4675);
FORCEPROP 1 LAST PATH I6
J 2
(900 4800);
DISPLAY 0.936170 (900 4800);
PAINT GREEN (900 4800);
DISPLAY INVISIBLE (900 4800);
FORCEADD TAP..6
R 2
(700 3750);
FORCEPROP 3 LASTPIN (650 3750) SIG_NAME M_M_DQS_DP<3>
J 0
(660 3760);
DISPLAY 0.659574 (660 3760);
PAINT MONO (660 3760);
DISPLAY INVISIBLE (660 3760);
FORCEPROP 1 LASTPIN (650 3750) BN 3
J 2
(700 3760);
DISPLAY 0.617021 (700 3760);
PAINT PINK (700 3760);
FORCEPROP 2 LAST CDS_LIB mstr_standard
J 0
(700 3750);
DISPLAY 0.787234 (700 3750);
PAINT MONO (700 3750);
DISPLAY INVISIBLE (700 3750);
FORCEPROP 1 LAST BODY_TYPE PLUMBING
J 2
(700 3700);
DISPLAY 1.234043 (700 3700);
PAINT GREEN (700 3700);
DISPLAY INVISIBLE (700 3700);
FORCEPROP 1 LAST HDL_TAP TRUE
J 2
(375 3625);
DISPLAY 1.234043 (375 3625);
PAINT GREEN (375 3625);
DISPLAY INVISIBLE (375 3625);
FORCEPROP 1 LAST PATH I60
J 2
(700 3750);
DISPLAY 0.936170 (700 3750);
PAINT GREEN (700 3750);
DISPLAY INVISIBLE (700 3750);
FORCEADD TAP..6
R 2
(700 3550);
FORCEPROP 3 LASTPIN (650 3550) SIG_NAME M_M_DQS_DP<1>
J 0
(660 3560);
DISPLAY 0.659574 (660 3560);
PAINT MONO (660 3560);
DISPLAY INVISIBLE (660 3560);
FORCEPROP 1 LASTPIN (650 3550) BN 1
J 2
(700 3560);
DISPLAY 0.617021 (700 3560);
PAINT PINK (700 3560);
FORCEPROP 2 LAST CDS_LIB mstr_standard
J 0
(700 3550);
DISPLAY 0.787234 (700 3550);
PAINT MONO (700 3550);
DISPLAY INVISIBLE (700 3550);
FORCEPROP 1 LAST BODY_TYPE PLUMBING
J 2
(700 3500);
DISPLAY 1.234043 (700 3500);
PAINT GREEN (700 3500);
DISPLAY INVISIBLE (700 3500);
FORCEPROP 1 LAST HDL_TAP TRUE
J 2
(375 3425);
DISPLAY 1.234043 (375 3425);
PAINT GREEN (375 3425);
DISPLAY INVISIBLE (375 3425);
FORCEPROP 1 LAST PATH I61
J 2
(700 3550);
DISPLAY 0.936170 (700 3550);
PAINT GREEN (700 3550);
DISPLAY INVISIBLE (700 3550);
FORCEADD TAP..6
R 2
(700 3650);
FORCEPROP 3 LASTPIN (650 3650) SIG_NAME M_M_DQS_DP<2>
J 0
(660 3660);
DISPLAY 0.659574 (660 3660);
PAINT MONO (660 3660);
DISPLAY INVISIBLE (660 3660);
FORCEPROP 1 LASTPIN (650 3650) BN 2
J 2
(700 3660);
DISPLAY 0.617021 (700 3660);
PAINT PINK (700 3660);
FORCEPROP 2 LAST CDS_LIB mstr_standard
J 0
(700 3650);
DISPLAY 0.787234 (700 3650);
PAINT MONO (700 3650);
DISPLAY INVISIBLE (700 3650);
FORCEPROP 1 LAST BODY_TYPE PLUMBING
J 2
(700 3600);
DISPLAY 1.234043 (700 3600);
PAINT GREEN (700 3600);
DISPLAY INVISIBLE (700 3600);
FORCEPROP 1 LAST HDL_TAP TRUE
J 2
(375 3525);
DISPLAY 1.234043 (375 3525);
PAINT GREEN (375 3525);
DISPLAY INVISIBLE (375 3525);
FORCEPROP 1 LAST PATH I62
J 2
(700 3650);
DISPLAY 0.936170 (700 3650);
PAINT GREEN (700 3650);
DISPLAY INVISIBLE (700 3650);
FORCEADD TAP..6
R 2
(700 3950);
FORCEPROP 3 LASTPIN (650 3950) SIG_NAME M_M_DQS_DP<5>
J 0
(660 3960);
DISPLAY 0.659574 (660 3960);
PAINT MONO (660 3960);
DISPLAY INVISIBLE (660 3960);
FORCEPROP 1 LASTPIN (650 3950) BN 5
J 2
(700 3960);
DISPLAY 0.617021 (700 3960);
PAINT PINK (700 3960);
FORCEPROP 2 LAST CDS_LIB mstr_standard
J 0
(700 3950);
DISPLAY 0.787234 (700 3950);
PAINT MONO (700 3950);
DISPLAY INVISIBLE (700 3950);
FORCEPROP 1 LAST BODY_TYPE PLUMBING
J 2
(700 3900);
DISPLAY 1.234043 (700 3900);
PAINT GREEN (700 3900);
DISPLAY INVISIBLE (700 3900);
FORCEPROP 1 LAST HDL_TAP TRUE
J 2
(375 3825);
DISPLAY 1.234043 (375 3825);
PAINT GREEN (375 3825);
DISPLAY INVISIBLE (375 3825);
FORCEPROP 1 LAST PATH I63
J 2
(700 3950);
DISPLAY 0.936170 (700 3950);
PAINT GREEN (700 3950);
DISPLAY INVISIBLE (700 3950);
FORCEADD TAP..6
R 2
(700 3850);
FORCEPROP 3 LASTPIN (650 3850) SIG_NAME M_M_DQS_DP<4>
J 0
(660 3860);
DISPLAY 0.659574 (660 3860);
PAINT MONO (660 3860);
DISPLAY INVISIBLE (660 3860);
FORCEPROP 1 LASTPIN (650 3850) BN 4
J 2
(700 3860);
DISPLAY 0.617021 (700 3860);
PAINT PINK (700 3860);
FORCEPROP 2 LAST CDS_LIB mstr_standard
J 0
(700 3850);
DISPLAY 0.787234 (700 3850);
PAINT MONO (700 3850);
DISPLAY INVISIBLE (700 3850);
FORCEPROP 1 LAST BODY_TYPE PLUMBING
J 2
(700 3800);
DISPLAY 1.234043 (700 3800);
PAINT GREEN (700 3800);
DISPLAY INVISIBLE (700 3800);
FORCEPROP 1 LAST HDL_TAP TRUE
J 2
(375 3725);
DISPLAY 1.234043 (375 3725);
PAINT GREEN (375 3725);
DISPLAY INVISIBLE (375 3725);
FORCEPROP 1 LAST PATH I64
J 2
(700 3850);
DISPLAY 0.936170 (700 3850);
PAINT GREEN (700 3850);
DISPLAY INVISIBLE (700 3850);
FORCEADD TAP..6
R 2
(700 3450);
FORCEPROP 3 LASTPIN (650 3450) SIG_NAME M_M_DQS_DP<0>
J 0
(660 3460);
DISPLAY 0.659574 (660 3460);
PAINT MONO (660 3460);
DISPLAY INVISIBLE (660 3460);
FORCEPROP 1 LASTPIN (650 3450) BN 0
J 2
(700 3460);
DISPLAY 0.617021 (700 3460);
PAINT PINK (700 3460);
FORCEPROP 2 LAST CDS_LIB mstr_standard
J 0
(700 3450);
DISPLAY 0.787234 (700 3450);
PAINT MONO (700 3450);
DISPLAY INVISIBLE (700 3450);
FORCEPROP 1 LAST BODY_TYPE PLUMBING
J 2
(700 3400);
DISPLAY 1.234043 (700 3400);
PAINT GREEN (700 3400);
DISPLAY INVISIBLE (700 3400);
FORCEPROP 1 LAST HDL_TAP TRUE
J 2
(375 3325);
DISPLAY 1.234043 (375 3325);
PAINT GREEN (375 3325);
DISPLAY INVISIBLE (375 3325);
FORCEPROP 1 LAST PATH I65
J 2
(700 3450);
DISPLAY 0.936170 (700 3450);
PAINT GREEN (700 3450);
DISPLAY INVISIBLE (700 3450);
FORCEADD TAP..6
R 2
(-1750 3900);
FORCEPROP 3 LASTPIN (-1800 3900) SIG_NAME M_M_DQ<42>
J 0
(-1790 3910);
DISPLAY 0.659574 (-1790 3910);
PAINT MONO (-1790 3910);
DISPLAY INVISIBLE (-1790 3910);
FORCEPROP 1 LASTPIN (-1800 3900) BN 42
J 2
(-1750 3910);
DISPLAY 0.617021 (-1750 3910);
PAINT PINK (-1750 3910);
FORCEPROP 2 LAST CDS_LIB mstr_standard
J 2
(-1750 3900);
DISPLAY 0.787234 (-1750 3900);
PAINT MONO (-1750 3900);
DISPLAY INVISIBLE (-1750 3900);
FORCEPROP 1 LAST BODY_TYPE PLUMBING
J 2
(-1750 3850);
DISPLAY 1.234043 (-1750 3850);
PAINT GREEN (-1750 3850);
DISPLAY INVISIBLE (-1750 3850);
FORCEPROP 1 LAST HDL_TAP TRUE
J 2
(-2075 3775);
DISPLAY 1.234043 (-2075 3775);
PAINT GREEN (-2075 3775);
DISPLAY INVISIBLE (-2075 3775);
FORCEPROP 1 LAST PATH I66
J 2
(-1750 3900);
DISPLAY 0.936170 (-1750 3900);
PAINT GREEN (-1750 3900);
DISPLAY INVISIBLE (-1750 3900);
FORCEADD TAP..6
R 2
(-1750 3850);
FORCEPROP 3 LASTPIN (-1800 3850) SIG_NAME M_M_DQ<43>
J 0
(-1790 3860);
DISPLAY 0.659574 (-1790 3860);
PAINT MONO (-1790 3860);
DISPLAY INVISIBLE (-1790 3860);
FORCEPROP 1 LASTPIN (-1800 3850) BN 43
J 2
(-1750 3860);
DISPLAY 0.617021 (-1750 3860);
PAINT PINK (-1750 3860);
FORCEPROP 2 LAST CDS_LIB mstr_standard
J 2
(-1750 3850);
DISPLAY 0.787234 (-1750 3850);
PAINT MONO (-1750 3850);
DISPLAY INVISIBLE (-1750 3850);
FORCEPROP 1 LAST BODY_TYPE PLUMBING
J 2
(-1750 3800);
DISPLAY 1.234043 (-1750 3800);
PAINT GREEN (-1750 3800);
DISPLAY INVISIBLE (-1750 3800);
FORCEPROP 1 LAST HDL_TAP TRUE
J 2
(-2075 3725);
DISPLAY 1.234043 (-2075 3725);
PAINT GREEN (-2075 3725);
DISPLAY INVISIBLE (-2075 3725);
FORCEPROP 1 LAST PATH I67
J 2
(-1750 3850);
DISPLAY 0.936170 (-1750 3850);
PAINT GREEN (-1750 3850);
DISPLAY INVISIBLE (-1750 3850);
FORCEADD TAP..6
R 2
(-1750 3750);
FORCEPROP 3 LASTPIN (-1800 3750) SIG_NAME M_M_DQ<41>
J 0
(-1790 3760);
DISPLAY 0.659574 (-1790 3760);
PAINT MONO (-1790 3760);
DISPLAY INVISIBLE (-1790 3760);
FORCEPROP 1 LASTPIN (-1800 3750) BN 41
J 2
(-1750 3760);
DISPLAY 0.617021 (-1750 3760);
PAINT PINK (-1750 3760);
FORCEPROP 2 LAST CDS_LIB mstr_standard
J 2
(-1750 3750);
DISPLAY 0.787234 (-1750 3750);
PAINT MONO (-1750 3750);
DISPLAY INVISIBLE (-1750 3750);
FORCEPROP 1 LAST BODY_TYPE PLUMBING
J 2
(-1750 3700);
DISPLAY 1.234043 (-1750 3700);
PAINT GREEN (-1750 3700);
DISPLAY INVISIBLE (-1750 3700);
FORCEPROP 1 LAST HDL_TAP TRUE
J 2
(-2075 3625);
DISPLAY 1.234043 (-2075 3625);
PAINT GREEN (-2075 3625);
DISPLAY INVISIBLE (-2075 3625);
FORCEPROP 1 LAST PATH I68
J 2
(-1750 3750);
DISPLAY 0.936170 (-1750 3750);
PAINT GREEN (-1750 3750);
DISPLAY INVISIBLE (-1750 3750);
FORCEADD TAP..6
R 2
(-1750 3800);
FORCEPROP 3 LASTPIN (-1800 3800) SIG_NAME M_M_DQ<40>
J 0
(-1790 3810);
DISPLAY 0.659574 (-1790 3810);
PAINT MONO (-1790 3810);
DISPLAY INVISIBLE (-1790 3810);
FORCEPROP 1 LASTPIN (-1800 3800) BN 40
J 2
(-1750 3810);
DISPLAY 0.617021 (-1750 3810);
PAINT PINK (-1750 3810);
FORCEPROP 2 LAST CDS_LIB mstr_standard
J 2
(-1750 3800);
DISPLAY 0.787234 (-1750 3800);
PAINT MONO (-1750 3800);
DISPLAY INVISIBLE (-1750 3800);
FORCEPROP 1 LAST BODY_TYPE PLUMBING
J 2
(-1750 3750);
DISPLAY 1.234043 (-1750 3750);
PAINT GREEN (-1750 3750);
DISPLAY INVISIBLE (-1750 3750);
FORCEPROP 1 LAST HDL_TAP TRUE
J 2
(-2075 3675);
DISPLAY 1.234043 (-2075 3675);
PAINT GREEN (-2075 3675);
DISPLAY INVISIBLE (-2075 3675);
FORCEPROP 1 LAST PATH I69
J 2
(-1750 3800);
DISPLAY 0.936170 (-1750 3800);
PAINT GREEN (-1750 3800);
DISPLAY INVISIBLE (-1750 3800);
FORCEADD TAP..6
R 2
(900 4700);
FORCEPROP 3 LASTPIN (850 4700) SIG_NAME M_M_DQS_DN<13>
J 0
(860 4710);
DISPLAY 0.659574 (860 4710);
PAINT MONO (860 4710);
DISPLAY INVISIBLE (860 4710);
FORCEPROP 1 LASTPIN (850 4700) BN 13
J 2
(900 4710);
DISPLAY 0.617021 (900 4710);
PAINT PINK (900 4710);
FORCEPROP 2 LAST CDS_LIB mstr_standard
J 0
(900 4700);
DISPLAY 0.787234 (900 4700);
PAINT MONO (900 4700);
DISPLAY INVISIBLE (900 4700);
FORCEPROP 1 LAST BODY_TYPE PLUMBING
J 2
(900 4650);
DISPLAY 1.234043 (900 4650);
PAINT GREEN (900 4650);
DISPLAY INVISIBLE (900 4650);
FORCEPROP 1 LAST HDL_TAP TRUE
J 2
(575 4575);
DISPLAY 1.234043 (575 4575);
PAINT GREEN (575 4575);
DISPLAY INVISIBLE (575 4575);
FORCEPROP 1 LAST PATH I7
J 2
(900 4700);
DISPLAY 0.936170 (900 4700);
PAINT GREEN (900 4700);
DISPLAY INVISIBLE (900 4700);
FORCEADD TAP..6
R 2
(-1750 3700);
FORCEPROP 3 LASTPIN (-1800 3700) SIG_NAME M_M_DQ<38>
J 0
(-1790 3710);
DISPLAY 0.659574 (-1790 3710);
PAINT MONO (-1790 3710);
DISPLAY INVISIBLE (-1790 3710);
FORCEPROP 1 LASTPIN (-1800 3700) BN 38
J 2
(-1750 3710);
DISPLAY 0.617021 (-1750 3710);
PAINT PINK (-1750 3710);
FORCEPROP 2 LAST CDS_LIB mstr_standard
J 2
(-1750 3700);
DISPLAY 0.787234 (-1750 3700);
PAINT MONO (-1750 3700);
DISPLAY INVISIBLE (-1750 3700);
FORCEPROP 1 LAST BODY_TYPE PLUMBING
J 2
(-1750 3650);
DISPLAY 1.234043 (-1750 3650);
PAINT GREEN (-1750 3650);
DISPLAY INVISIBLE (-1750 3650);
FORCEPROP 1 LAST HDL_TAP TRUE
J 2
(-2075 3575);
DISPLAY 1.234043 (-2075 3575);
PAINT GREEN (-2075 3575);
DISPLAY INVISIBLE (-2075 3575);
FORCEPROP 1 LAST PATH I70
J 2
(-1750 3700);
DISPLAY 0.936170 (-1750 3700);
PAINT GREEN (-1750 3700);
DISPLAY INVISIBLE (-1750 3700);
FORCEADD TAP..6
R 2
(-1750 3650);
FORCEPROP 3 LASTPIN (-1800 3650) SIG_NAME M_M_DQ<39>
J 0
(-1790 3660);
DISPLAY 0.659574 (-1790 3660);
PAINT MONO (-1790 3660);
DISPLAY INVISIBLE (-1790 3660);
FORCEPROP 1 LASTPIN (-1800 3650) BN 39
J 2
(-1750 3660);
DISPLAY 0.617021 (-1750 3660);
PAINT PINK (-1750 3660);
FORCEPROP 2 LAST CDS_LIB mstr_standard
J 2
(-1750 3650);
DISPLAY 0.787234 (-1750 3650);
PAINT MONO (-1750 3650);
DISPLAY INVISIBLE (-1750 3650);
FORCEPROP 1 LAST BODY_TYPE PLUMBING
J 2
(-1750 3600);
DISPLAY 1.234043 (-1750 3600);
PAINT GREEN (-1750 3600);
DISPLAY INVISIBLE (-1750 3600);
FORCEPROP 1 LAST HDL_TAP TRUE
J 2
(-2075 3525);
DISPLAY 1.234043 (-2075 3525);
PAINT GREEN (-2075 3525);
DISPLAY INVISIBLE (-2075 3525);
FORCEPROP 1 LAST PATH I71
J 2
(-1750 3650);
DISPLAY 0.936170 (-1750 3650);
PAINT GREEN (-1750 3650);
DISPLAY INVISIBLE (-1750 3650);
FORCEADD TAP..6
R 2
(-1750 3600);
FORCEPROP 3 LASTPIN (-1800 3600) SIG_NAME M_M_DQ<36>
J 0
(-1790 3610);
DISPLAY 0.659574 (-1790 3610);
PAINT MONO (-1790 3610);
DISPLAY INVISIBLE (-1790 3610);
FORCEPROP 1 LASTPIN (-1800 3600) BN 36
J 2
(-1750 3610);
DISPLAY 0.617021 (-1750 3610);
PAINT PINK (-1750 3610);
FORCEPROP 2 LAST CDS_LIB mstr_standard
J 2
(-1750 3600);
DISPLAY 0.787234 (-1750 3600);
PAINT MONO (-1750 3600);
DISPLAY INVISIBLE (-1750 3600);
FORCEPROP 1 LAST BODY_TYPE PLUMBING
J 2
(-1750 3550);
DISPLAY 1.234043 (-1750 3550);
PAINT GREEN (-1750 3550);
DISPLAY INVISIBLE (-1750 3550);
FORCEPROP 1 LAST HDL_TAP TRUE
J 2
(-2075 3475);
DISPLAY 1.234043 (-2075 3475);
PAINT GREEN (-2075 3475);
DISPLAY INVISIBLE (-2075 3475);
FORCEPROP 1 LAST PATH I72
J 2
(-1750 3600);
DISPLAY 0.936170 (-1750 3600);
PAINT GREEN (-1750 3600);
DISPLAY INVISIBLE (-1750 3600);
FORCEADD TAP..6
R 2
(-1750 3550);
FORCEPROP 3 LASTPIN (-1800 3550) SIG_NAME M_M_DQ<37>
J 0
(-1790 3560);
DISPLAY 0.659574 (-1790 3560);
PAINT MONO (-1790 3560);
DISPLAY INVISIBLE (-1790 3560);
FORCEPROP 1 LASTPIN (-1800 3550) BN 37
J 2
(-1750 3560);
DISPLAY 0.617021 (-1750 3560);
PAINT PINK (-1750 3560);
FORCEPROP 2 LAST CDS_LIB mstr_standard
J 2
(-1750 3550);
DISPLAY 0.787234 (-1750 3550);
PAINT MONO (-1750 3550);
DISPLAY INVISIBLE (-1750 3550);
FORCEPROP 1 LAST BODY_TYPE PLUMBING
J 2
(-1750 3500);
DISPLAY 1.234043 (-1750 3500);
PAINT GREEN (-1750 3500);
DISPLAY INVISIBLE (-1750 3500);
FORCEPROP 1 LAST HDL_TAP TRUE
J 2
(-2075 3425);
DISPLAY 1.234043 (-2075 3425);
PAINT GREEN (-2075 3425);
DISPLAY INVISIBLE (-2075 3425);
FORCEPROP 1 LAST PATH I73
J 2
(-1750 3550);
DISPLAY 0.936170 (-1750 3550);
PAINT GREEN (-1750 3550);
DISPLAY INVISIBLE (-1750 3550);
FORCEADD TAP..6
R 2
(-1750 3500);
FORCEPROP 3 LASTPIN (-1800 3500) SIG_NAME M_M_DQ<34>
J 0
(-1790 3510);
DISPLAY 0.659574 (-1790 3510);
PAINT MONO (-1790 3510);
DISPLAY INVISIBLE (-1790 3510);
FORCEPROP 1 LASTPIN (-1800 3500) BN 34
J 2
(-1750 3510);
DISPLAY 0.617021 (-1750 3510);
PAINT PINK (-1750 3510);
FORCEPROP 2 LAST CDS_LIB mstr_standard
J 2
(-1750 3500);
DISPLAY 0.787234 (-1750 3500);
PAINT MONO (-1750 3500);
DISPLAY INVISIBLE (-1750 3500);
FORCEPROP 1 LAST BODY_TYPE PLUMBING
J 2
(-1750 3450);
DISPLAY 1.234043 (-1750 3450);
PAINT GREEN (-1750 3450);
DISPLAY INVISIBLE (-1750 3450);
FORCEPROP 1 LAST HDL_TAP TRUE
J 2
(-2075 3375);
DISPLAY 1.234043 (-2075 3375);
PAINT GREEN (-2075 3375);
DISPLAY INVISIBLE (-2075 3375);
FORCEPROP 1 LAST PATH I74
J 2
(-1750 3500);
DISPLAY 0.936170 (-1750 3500);
PAINT GREEN (-1750 3500);
DISPLAY INVISIBLE (-1750 3500);
FORCEADD TAP..6
R 2
(-1750 3450);
FORCEPROP 3 LASTPIN (-1800 3450) SIG_NAME M_M_DQ<35>
J 0
(-1790 3460);
DISPLAY 0.659574 (-1790 3460);
PAINT MONO (-1790 3460);
DISPLAY INVISIBLE (-1790 3460);
FORCEPROP 1 LASTPIN (-1800 3450) BN 35
J 2
(-1750 3460);
DISPLAY 0.617021 (-1750 3460);
PAINT PINK (-1750 3460);
FORCEPROP 2 LAST CDS_LIB mstr_standard
J 2
(-1750 3450);
DISPLAY 0.787234 (-1750 3450);
PAINT MONO (-1750 3450);
DISPLAY INVISIBLE (-1750 3450);
FORCEPROP 1 LAST BODY_TYPE PLUMBING
J 2
(-1750 3400);
DISPLAY 1.234043 (-1750 3400);
PAINT GREEN (-1750 3400);
DISPLAY INVISIBLE (-1750 3400);
FORCEPROP 1 LAST HDL_TAP TRUE
J 2
(-2075 3325);
DISPLAY 1.234043 (-2075 3325);
PAINT GREEN (-2075 3325);
DISPLAY INVISIBLE (-2075 3325);
FORCEPROP 1 LAST PATH I75
J 2
(-1750 3450);
DISPLAY 0.936170 (-1750 3450);
PAINT GREEN (-1750 3450);
DISPLAY INVISIBLE (-1750 3450);
FORCEADD TAP..6
R 2
(-1750 3400);
FORCEPROP 3 LASTPIN (-1800 3400) SIG_NAME M_M_DQ<32>
J 0
(-1790 3410);
DISPLAY 0.659574 (-1790 3410);
PAINT MONO (-1790 3410);
DISPLAY INVISIBLE (-1790 3410);
FORCEPROP 1 LASTPIN (-1800 3400) BN 32
J 2
(-1750 3410);
DISPLAY 0.617021 (-1750 3410);
PAINT PINK (-1750 3410);
FORCEPROP 2 LAST CDS_LIB mstr_standard
J 2
(-1750 3400);
DISPLAY 0.787234 (-1750 3400);
PAINT MONO (-1750 3400);
DISPLAY INVISIBLE (-1750 3400);
FORCEPROP 1 LAST BODY_TYPE PLUMBING
J 2
(-1750 3350);
DISPLAY 1.234043 (-1750 3350);
PAINT GREEN (-1750 3350);
DISPLAY INVISIBLE (-1750 3350);
FORCEPROP 1 LAST HDL_TAP TRUE
J 2
(-2075 3275);
DISPLAY 1.234043 (-2075 3275);
PAINT GREEN (-2075 3275);
DISPLAY INVISIBLE (-2075 3275);
FORCEPROP 1 LAST PATH I76
J 2
(-1750 3400);
DISPLAY 0.936170 (-1750 3400);
PAINT GREEN (-1750 3400);
DISPLAY INVISIBLE (-1750 3400);
FORCEADD TAP..6
R 2
(-1750 3350);
FORCEPROP 3 LASTPIN (-1800 3350) SIG_NAME M_M_DQ<33>
J 0
(-1790 3360);
DISPLAY 0.659574 (-1790 3360);
PAINT MONO (-1790 3360);
DISPLAY INVISIBLE (-1790 3360);
FORCEPROP 1 LASTPIN (-1800 3350) BN 33
J 2
(-1750 3360);
DISPLAY 0.617021 (-1750 3360);
PAINT PINK (-1750 3360);
FORCEPROP 2 LAST CDS_LIB mstr_standard
J 2
(-1750 3350);
DISPLAY 0.787234 (-1750 3350);
PAINT MONO (-1750 3350);
DISPLAY INVISIBLE (-1750 3350);
FORCEPROP 1 LAST BODY_TYPE PLUMBING
J 2
(-1750 3300);
DISPLAY 1.234043 (-1750 3300);
PAINT GREEN (-1750 3300);
DISPLAY INVISIBLE (-1750 3300);
FORCEPROP 1 LAST HDL_TAP TRUE
J 2
(-2075 3225);
DISPLAY 1.234043 (-2075 3225);
PAINT GREEN (-2075 3225);
DISPLAY INVISIBLE (-2075 3225);
FORCEPROP 1 LAST PATH I77
J 2
(-1750 3350);
DISPLAY 0.936170 (-1750 3350);
PAINT GREEN (-1750 3350);
DISPLAY INVISIBLE (-1750 3350);
FORCEADD TAP..6
R 2
(-1750 3200);
FORCEPROP 3 LASTPIN (-1800 3200) SIG_NAME M_M_DQ<28>
J 0
(-1790 3210);
DISPLAY 0.659574 (-1790 3210);
PAINT MONO (-1790 3210);
DISPLAY INVISIBLE (-1790 3210);
FORCEPROP 1 LASTPIN (-1800 3200) BN 28
J 2
(-1750 3210);
DISPLAY 0.617021 (-1750 3210);
PAINT PINK (-1750 3210);
FORCEPROP 2 LAST CDS_LIB mstr_standard
J 2
(-1750 3200);
DISPLAY 0.787234 (-1750 3200);
PAINT MONO (-1750 3200);
DISPLAY INVISIBLE (-1750 3200);
FORCEPROP 1 LAST BODY_TYPE PLUMBING
J 2
(-1750 3150);
DISPLAY 1.234043 (-1750 3150);
PAINT GREEN (-1750 3150);
DISPLAY INVISIBLE (-1750 3150);
FORCEPROP 1 LAST HDL_TAP TRUE
J 2
(-2075 3075);
DISPLAY 1.234043 (-2075 3075);
PAINT GREEN (-2075 3075);
DISPLAY INVISIBLE (-2075 3075);
FORCEPROP 1 LAST PATH I78
J 2
(-1750 3200);
DISPLAY 0.936170 (-1750 3200);
PAINT GREEN (-1750 3200);
DISPLAY INVISIBLE (-1750 3200);
FORCEADD TAP..6
R 2
(-1750 3250);
FORCEPROP 3 LASTPIN (-1800 3250) SIG_NAME M_M_DQ<31>
J 0
(-1790 3260);
DISPLAY 0.659574 (-1790 3260);
PAINT MONO (-1790 3260);
DISPLAY INVISIBLE (-1790 3260);
FORCEPROP 1 LASTPIN (-1800 3250) BN 31
J 2
(-1750 3260);
DISPLAY 0.617021 (-1750 3260);
PAINT PINK (-1750 3260);
FORCEPROP 2 LAST CDS_LIB mstr_standard
J 2
(-1750 3250);
DISPLAY 0.787234 (-1750 3250);
PAINT MONO (-1750 3250);
DISPLAY INVISIBLE (-1750 3250);
FORCEPROP 1 LAST BODY_TYPE PLUMBING
J 2
(-1750 3200);
DISPLAY 1.234043 (-1750 3200);
PAINT GREEN (-1750 3200);
DISPLAY INVISIBLE (-1750 3200);
FORCEPROP 1 LAST HDL_TAP TRUE
J 2
(-2075 3125);
DISPLAY 1.234043 (-2075 3125);
PAINT GREEN (-2075 3125);
DISPLAY INVISIBLE (-2075 3125);
FORCEPROP 1 LAST PATH I79
J 2
(-1750 3250);
DISPLAY 0.936170 (-1750 3250);
PAINT GREEN (-1750 3250);
DISPLAY INVISIBLE (-1750 3250);
FORCEADD TAP..6
R 2
(900 4600);
FORCEPROP 3 LASTPIN (850 4600) SIG_NAME M_M_DQS_DN<12>
J 0
(860 4610);
DISPLAY 0.659574 (860 4610);
PAINT MONO (860 4610);
DISPLAY INVISIBLE (860 4610);
FORCEPROP 1 LASTPIN (850 4600) BN 12
J 2
(900 4610);
DISPLAY 0.617021 (900 4610);
PAINT PINK (900 4610);
FORCEPROP 2 LAST CDS_LIB mstr_standard
J 0
(900 4600);
DISPLAY 0.787234 (900 4600);
PAINT MONO (900 4600);
DISPLAY INVISIBLE (900 4600);
FORCEPROP 1 LAST BODY_TYPE PLUMBING
J 2
(900 4550);
DISPLAY 1.234043 (900 4550);
PAINT GREEN (900 4550);
DISPLAY INVISIBLE (900 4550);
FORCEPROP 1 LAST HDL_TAP TRUE
J 2
(575 4475);
DISPLAY 1.234043 (575 4475);
PAINT GREEN (575 4475);
DISPLAY INVISIBLE (575 4475);
FORCEPROP 1 LAST PATH I8
J 2
(900 4600);
DISPLAY 0.936170 (900 4600);
PAINT GREEN (900 4600);
DISPLAY INVISIBLE (900 4600);
FORCEADD TAP..6
R 2
(-1750 3300);
FORCEPROP 3 LASTPIN (-1800 3300) SIG_NAME M_M_DQ<30>
J 0
(-1790 3310);
DISPLAY 0.659574 (-1790 3310);
PAINT MONO (-1790 3310);
DISPLAY INVISIBLE (-1790 3310);
FORCEPROP 1 LASTPIN (-1800 3300) BN 30
J 2
(-1750 3310);
DISPLAY 0.617021 (-1750 3310);
PAINT PINK (-1750 3310);
FORCEPROP 2 LAST CDS_LIB mstr_standard
J 2
(-1750 3300);
DISPLAY 0.787234 (-1750 3300);
PAINT MONO (-1750 3300);
DISPLAY INVISIBLE (-1750 3300);
FORCEPROP 1 LAST BODY_TYPE PLUMBING
J 2
(-1750 3250);
DISPLAY 1.234043 (-1750 3250);
PAINT GREEN (-1750 3250);
DISPLAY INVISIBLE (-1750 3250);
FORCEPROP 1 LAST HDL_TAP TRUE
J 2
(-2075 3175);
DISPLAY 1.234043 (-2075 3175);
PAINT GREEN (-2075 3175);
DISPLAY INVISIBLE (-2075 3175);
FORCEPROP 1 LAST PATH I80
J 2
(-1750 3300);
DISPLAY 0.936170 (-1750 3300);
PAINT GREEN (-1750 3300);
DISPLAY INVISIBLE (-1750 3300);
FORCEADD TAP..6
R 2
(-1750 2900);
FORCEPROP 3 LASTPIN (-1800 2900) SIG_NAME M_M_DQ<22>
J 0
(-1790 2910);
DISPLAY 0.659574 (-1790 2910);
PAINT MONO (-1790 2910);
DISPLAY INVISIBLE (-1790 2910);
FORCEPROP 1 LASTPIN (-1800 2900) BN 22
J 2
(-1750 2910);
DISPLAY 0.617021 (-1750 2910);
PAINT PINK (-1750 2910);
FORCEPROP 2 LAST CDS_LIB mstr_standard
J 2
(-1750 2900);
DISPLAY 0.787234 (-1750 2900);
PAINT MONO (-1750 2900);
DISPLAY INVISIBLE (-1750 2900);
FORCEPROP 1 LAST BODY_TYPE PLUMBING
J 2
(-1750 2850);
DISPLAY 1.234043 (-1750 2850);
PAINT GREEN (-1750 2850);
DISPLAY INVISIBLE (-1750 2850);
FORCEPROP 1 LAST HDL_TAP TRUE
J 2
(-2075 2775);
DISPLAY 1.234043 (-2075 2775);
PAINT GREEN (-2075 2775);
DISPLAY INVISIBLE (-2075 2775);
FORCEPROP 1 LAST PATH I81
J 2
(-1750 2900);
DISPLAY 0.936170 (-1750 2900);
PAINT GREEN (-1750 2900);
DISPLAY INVISIBLE (-1750 2900);
FORCEADD TAP..6
R 2
(-1750 3100);
FORCEPROP 3 LASTPIN (-1800 3100) SIG_NAME M_M_DQ<26>
J 0
(-1790 3110);
DISPLAY 0.659574 (-1790 3110);
PAINT MONO (-1790 3110);
DISPLAY INVISIBLE (-1790 3110);
FORCEPROP 1 LASTPIN (-1800 3100) BN 26
J 2
(-1750 3110);
DISPLAY 0.617021 (-1750 3110);
PAINT PINK (-1750 3110);
FORCEPROP 2 LAST CDS_LIB mstr_standard
J 2
(-1750 3100);
DISPLAY 0.787234 (-1750 3100);
PAINT MONO (-1750 3100);
DISPLAY INVISIBLE (-1750 3100);
FORCEPROP 1 LAST BODY_TYPE PLUMBING
J 2
(-1750 3050);
DISPLAY 1.234043 (-1750 3050);
PAINT GREEN (-1750 3050);
DISPLAY INVISIBLE (-1750 3050);
FORCEPROP 1 LAST HDL_TAP TRUE
J 2
(-2075 2975);
DISPLAY 1.234043 (-2075 2975);
PAINT GREEN (-2075 2975);
DISPLAY INVISIBLE (-2075 2975);
FORCEPROP 1 LAST PATH I82
J 2
(-1750 3100);
DISPLAY 0.936170 (-1750 3100);
PAINT GREEN (-1750 3100);
DISPLAY INVISIBLE (-1750 3100);
FORCEADD TAP..6
R 2
(-1750 3150);
FORCEPROP 3 LASTPIN (-1800 3150) SIG_NAME M_M_DQ<29>
J 0
(-1790 3160);
DISPLAY 0.659574 (-1790 3160);
PAINT MONO (-1790 3160);
DISPLAY INVISIBLE (-1790 3160);
FORCEPROP 1 LASTPIN (-1800 3150) BN 29
J 2
(-1750 3160);
DISPLAY 0.617021 (-1750 3160);
PAINT PINK (-1750 3160);
FORCEPROP 2 LAST CDS_LIB mstr_standard
J 2
(-1750 3150);
DISPLAY 0.787234 (-1750 3150);
PAINT MONO (-1750 3150);
DISPLAY INVISIBLE (-1750 3150);
FORCEPROP 1 LAST BODY_TYPE PLUMBING
J 2
(-1750 3100);
DISPLAY 1.234043 (-1750 3100);
PAINT GREEN (-1750 3100);
DISPLAY INVISIBLE (-1750 3100);
FORCEPROP 1 LAST HDL_TAP TRUE
J 2
(-2075 3025);
DISPLAY 1.234043 (-2075 3025);
PAINT GREEN (-2075 3025);
DISPLAY INVISIBLE (-2075 3025);
FORCEPROP 1 LAST PATH I83
J 2
(-1750 3150);
DISPLAY 0.936170 (-1750 3150);
PAINT GREEN (-1750 3150);
DISPLAY INVISIBLE (-1750 3150);
FORCEADD TAP..6
R 2
(-1750 3050);
FORCEPROP 3 LASTPIN (-1800 3050) SIG_NAME M_M_DQ<27>
J 0
(-1790 3060);
DISPLAY 0.659574 (-1790 3060);
PAINT MONO (-1790 3060);
DISPLAY INVISIBLE (-1790 3060);
FORCEPROP 1 LASTPIN (-1800 3050) BN 27
J 2
(-1750 3060);
DISPLAY 0.617021 (-1750 3060);
PAINT PINK (-1750 3060);
FORCEPROP 2 LAST CDS_LIB mstr_standard
J 2
(-1750 3050);
DISPLAY 0.787234 (-1750 3050);
PAINT MONO (-1750 3050);
DISPLAY INVISIBLE (-1750 3050);
FORCEPROP 1 LAST BODY_TYPE PLUMBING
J 2
(-1750 3000);
DISPLAY 1.234043 (-1750 3000);
PAINT GREEN (-1750 3000);
DISPLAY INVISIBLE (-1750 3000);
FORCEPROP 1 LAST HDL_TAP TRUE
J 2
(-2075 2925);
DISPLAY 1.234043 (-2075 2925);
PAINT GREEN (-2075 2925);
DISPLAY INVISIBLE (-2075 2925);
FORCEPROP 1 LAST PATH I84
J 2
(-1750 3050);
DISPLAY 0.936170 (-1750 3050);
PAINT GREEN (-1750 3050);
DISPLAY INVISIBLE (-1750 3050);
FORCEADD TAP..6
R 2
(-1750 3000);
FORCEPROP 3 LASTPIN (-1800 3000) SIG_NAME M_M_DQ<24>
J 0
(-1790 3010);
DISPLAY 0.659574 (-1790 3010);
PAINT MONO (-1790 3010);
DISPLAY INVISIBLE (-1790 3010);
FORCEPROP 1 LASTPIN (-1800 3000) BN 24
J 2
(-1750 3010);
DISPLAY 0.617021 (-1750 3010);
PAINT PINK (-1750 3010);
FORCEPROP 2 LAST CDS_LIB mstr_standard
J 2
(-1750 3000);
DISPLAY 0.787234 (-1750 3000);
PAINT MONO (-1750 3000);
DISPLAY INVISIBLE (-1750 3000);
FORCEPROP 1 LAST BODY_TYPE PLUMBING
J 2
(-1750 2950);
DISPLAY 1.234043 (-1750 2950);
PAINT GREEN (-1750 2950);
DISPLAY INVISIBLE (-1750 2950);
FORCEPROP 1 LAST HDL_TAP TRUE
J 2
(-2075 2875);
DISPLAY 1.234043 (-2075 2875);
PAINT GREEN (-2075 2875);
DISPLAY INVISIBLE (-2075 2875);
FORCEPROP 1 LAST PATH I85
J 2
(-1750 3000);
DISPLAY 0.936170 (-1750 3000);
PAINT GREEN (-1750 3000);
DISPLAY INVISIBLE (-1750 3000);
FORCEADD TAP..6
R 2
(-1750 2950);
FORCEPROP 3 LASTPIN (-1800 2950) SIG_NAME M_M_DQ<25>
J 0
(-1790 2960);
DISPLAY 0.659574 (-1790 2960);
PAINT MONO (-1790 2960);
DISPLAY INVISIBLE (-1790 2960);
FORCEPROP 1 LASTPIN (-1800 2950) BN 25
J 2
(-1750 2960);
DISPLAY 0.617021 (-1750 2960);
PAINT PINK (-1750 2960);
FORCEPROP 2 LAST CDS_LIB mstr_standard
J 2
(-1750 2950);
DISPLAY 0.787234 (-1750 2950);
PAINT MONO (-1750 2950);
DISPLAY INVISIBLE (-1750 2950);
FORCEPROP 1 LAST BODY_TYPE PLUMBING
J 2
(-1750 2900);
DISPLAY 1.234043 (-1750 2900);
PAINT GREEN (-1750 2900);
DISPLAY INVISIBLE (-1750 2900);
FORCEPROP 1 LAST HDL_TAP TRUE
J 2
(-2075 2825);
DISPLAY 1.234043 (-2075 2825);
PAINT GREEN (-2075 2825);
DISPLAY INVISIBLE (-2075 2825);
FORCEPROP 1 LAST PATH I86
J 2
(-1750 2950);
DISPLAY 0.936170 (-1750 2950);
PAINT GREEN (-1750 2950);
DISPLAY INVISIBLE (-1750 2950);
FORCEADD TAP..6
R 2
(-1750 2650);
FORCEPROP 3 LASTPIN (-1800 2650) SIG_NAME M_M_DQ<19>
J 0
(-1790 2660);
DISPLAY 0.659574 (-1790 2660);
PAINT MONO (-1790 2660);
DISPLAY INVISIBLE (-1790 2660);
FORCEPROP 1 LASTPIN (-1800 2650) BN 19
J 2
(-1750 2660);
DISPLAY 0.617021 (-1750 2660);
PAINT PINK (-1750 2660);
FORCEPROP 2 LAST CDS_LIB mstr_standard
J 2
(-1750 2650);
DISPLAY 0.787234 (-1750 2650);
PAINT MONO (-1750 2650);
DISPLAY INVISIBLE (-1750 2650);
FORCEPROP 1 LAST BODY_TYPE PLUMBING
J 2
(-1750 2600);
DISPLAY 1.234043 (-1750 2600);
PAINT GREEN (-1750 2600);
DISPLAY INVISIBLE (-1750 2600);
FORCEPROP 1 LAST HDL_TAP TRUE
J 2
(-2075 2525);
DISPLAY 1.234043 (-2075 2525);
PAINT GREEN (-2075 2525);
DISPLAY INVISIBLE (-2075 2525);
FORCEPROP 1 LAST PATH I88
J 2
(-1750 2650);
DISPLAY 0.936170 (-1750 2650);
PAINT GREEN (-1750 2650);
DISPLAY INVISIBLE (-1750 2650);
FORCEADD TAP..6
R 2
(-1750 2850);
FORCEPROP 3 LASTPIN (-1800 2850) SIG_NAME M_M_DQ<23>
J 0
(-1790 2860);
DISPLAY 0.659574 (-1790 2860);
PAINT MONO (-1790 2860);
DISPLAY INVISIBLE (-1790 2860);
FORCEPROP 1 LASTPIN (-1800 2850) BN 23
J 2
(-1750 2860);
DISPLAY 0.617021 (-1750 2860);
PAINT PINK (-1750 2860);
FORCEPROP 2 LAST CDS_LIB mstr_standard
J 2
(-1750 2850);
DISPLAY 0.787234 (-1750 2850);
PAINT MONO (-1750 2850);
DISPLAY INVISIBLE (-1750 2850);
FORCEPROP 1 LAST BODY_TYPE PLUMBING
J 2
(-1750 2800);
DISPLAY 1.234043 (-1750 2800);
PAINT GREEN (-1750 2800);
DISPLAY INVISIBLE (-1750 2800);
FORCEPROP 1 LAST HDL_TAP TRUE
J 2
(-2075 2725);
DISPLAY 1.234043 (-2075 2725);
PAINT GREEN (-2075 2725);
DISPLAY INVISIBLE (-2075 2725);
FORCEPROP 1 LAST PATH I89
J 2
(-1750 2850);
DISPLAY 0.936170 (-1750 2850);
PAINT GREEN (-1750 2850);
DISPLAY INVISIBLE (-1750 2850);
FORCEADD PVTT_KLM..1
(-1250 2750);
FORCEPROP 3 LASTPIN (-1250 2700) SIG_NAME PVTT_KLM\g
J 0
(-1240 2710);
DISPLAY 0.659574 (-1240 2710);
PAINT MONO (-1240 2710);
DISPLAY INVISIBLE (-1240 2710);
FORCEPROP 1 LAST VOLTAGE 0.6V
J 0
(-1295 2707);
DISPLAY 0.340426 (-1295 2707);
PAINT SKYBLUE (-1295 2707);
DISPLAY INVISIBLE (-1295 2707);
FORCEPROP 2 LAST BOM_COST MEM
J 0
(-1250 2755);
PAINT ORANGE (-1250 2755);
DISPLAY INVISIBLE (-1250 2755);
FORCEPROP 2 LAST CDS_LIB mstr_symbols
J 0
(-1250 2750);
PAINT ORANGE (-1250 2750);
DISPLAY INVISIBLE (-1250 2750);
FORCEPROP 1 LAST BODY_TYPE PLUMBING
J 0
(-1295 2707);
DISPLAY 0.340426 (-1295 2707);
PAINT GREEN (-1295 2707);
DISPLAY INVISIBLE (-1295 2707);
FORCEPROP 1 LAST PATH I9
J 0
(-1200 2775);
DISPLAY 0.872340 (-1200 2775);
PAINT AQUA (-1200 2775);
DISPLAY INVISIBLE (-1200 2775);
FORCEPROP 2 LAST ROOM DDR4_CH_D
J 0
(-1250 2850);
DISPLAY 0.787234 (-1250 2850);
PAINT ORANGE (-1250 2850);
DISPLAY INVISIBLE (-1250 2850);
FORCEPROP 1 LAST HDL_POWER PVTT_KLM
J 1
(-1250 2800);
DISPLAY 0.872340 (-1250 2800);
PAINT GREEN (-1250 2800);
DISPLAY INVISIBLE (-1250 2800);
FORCEADD TAP..6
R 2
(-1750 2800);
FORCEPROP 3 LASTPIN (-1800 2800) SIG_NAME M_M_DQ<20>
J 0
(-1790 2810);
DISPLAY 0.659574 (-1790 2810);
PAINT MONO (-1790 2810);
DISPLAY INVISIBLE (-1790 2810);
FORCEPROP 1 LASTPIN (-1800 2800) BN 20
J 2
(-1750 2810);
DISPLAY 0.617021 (-1750 2810);
PAINT PINK (-1750 2810);
FORCEPROP 2 LAST CDS_LIB mstr_standard
J 2
(-1750 2800);
DISPLAY 0.787234 (-1750 2800);
PAINT MONO (-1750 2800);
DISPLAY INVISIBLE (-1750 2800);
FORCEPROP 1 LAST BODY_TYPE PLUMBING
J 2
(-1750 2750);
DISPLAY 1.234043 (-1750 2750);
PAINT GREEN (-1750 2750);
DISPLAY INVISIBLE (-1750 2750);
FORCEPROP 1 LAST HDL_TAP TRUE
J 2
(-2075 2675);
DISPLAY 1.234043 (-2075 2675);
PAINT GREEN (-2075 2675);
DISPLAY INVISIBLE (-2075 2675);
FORCEPROP 1 LAST PATH I90
J 2
(-1750 2800);
DISPLAY 0.936170 (-1750 2800);
PAINT GREEN (-1750 2800);
DISPLAY INVISIBLE (-1750 2800);
FORCEADD TAP..6
R 2
(-1750 2700);
FORCEPROP 3 LASTPIN (-1800 2700) SIG_NAME M_M_DQ<18>
J 0
(-1790 2710);
DISPLAY 0.659574 (-1790 2710);
PAINT MONO (-1790 2710);
DISPLAY INVISIBLE (-1790 2710);
FORCEPROP 1 LASTPIN (-1800 2700) BN 18
J 2
(-1750 2710);
DISPLAY 0.617021 (-1750 2710);
PAINT PINK (-1750 2710);
FORCEPROP 2 LAST CDS_LIB mstr_standard
J 2
(-1750 2700);
DISPLAY 0.787234 (-1750 2700);
PAINT MONO (-1750 2700);
DISPLAY INVISIBLE (-1750 2700);
FORCEPROP 1 LAST BODY_TYPE PLUMBING
J 2
(-1750 2650);
DISPLAY 1.234043 (-1750 2650);
PAINT GREEN (-1750 2650);
DISPLAY INVISIBLE (-1750 2650);
FORCEPROP 1 LAST HDL_TAP TRUE
J 2
(-2075 2575);
DISPLAY 1.234043 (-2075 2575);
PAINT GREEN (-2075 2575);
DISPLAY INVISIBLE (-2075 2575);
FORCEPROP 1 LAST PATH I91
J 2
(-1750 2700);
DISPLAY 0.936170 (-1750 2700);
PAINT GREEN (-1750 2700);
DISPLAY INVISIBLE (-1750 2700);
FORCEADD TAP..6
R 2
(-1750 2750);
FORCEPROP 3 LASTPIN (-1800 2750) SIG_NAME M_M_DQ<21>
J 0
(-1790 2760);
DISPLAY 0.659574 (-1790 2760);
PAINT MONO (-1790 2760);
DISPLAY INVISIBLE (-1790 2760);
FORCEPROP 1 LASTPIN (-1800 2750) BN 21
J 2
(-1750 2760);
DISPLAY 0.617021 (-1750 2760);
PAINT PINK (-1750 2760);
FORCEPROP 2 LAST CDS_LIB mstr_standard
J 2
(-1750 2750);
DISPLAY 0.787234 (-1750 2750);
PAINT MONO (-1750 2750);
DISPLAY INVISIBLE (-1750 2750);
FORCEPROP 1 LAST BODY_TYPE PLUMBING
J 2
(-1750 2700);
DISPLAY 1.234043 (-1750 2700);
PAINT GREEN (-1750 2700);
DISPLAY INVISIBLE (-1750 2700);
FORCEPROP 1 LAST HDL_TAP TRUE
J 2
(-2075 2625);
DISPLAY 1.234043 (-2075 2625);
PAINT GREEN (-2075 2625);
DISPLAY INVISIBLE (-2075 2625);
FORCEPROP 1 LAST PATH I92
J 2
(-1750 2750);
DISPLAY 0.936170 (-1750 2750);
PAINT GREEN (-1750 2750);
DISPLAY INVISIBLE (-1750 2750);
FORCEADD TAP..6
R 2
(-1750 2400);
FORCEPROP 3 LASTPIN (-1800 2400) SIG_NAME M_M_DQ<12>
J 0
(-1790 2410);
DISPLAY 0.659574 (-1790 2410);
PAINT MONO (-1790 2410);
DISPLAY INVISIBLE (-1790 2410);
FORCEPROP 1 LASTPIN (-1800 2400) BN 12
J 2
(-1750 2410);
DISPLAY 0.617021 (-1750 2410);
PAINT PINK (-1750 2410);
FORCEPROP 2 LAST CDS_LIB mstr_standard
J 2
(-1750 2400);
DISPLAY 0.787234 (-1750 2400);
PAINT MONO (-1750 2400);
DISPLAY INVISIBLE (-1750 2400);
FORCEPROP 1 LAST BODY_TYPE PLUMBING
J 2
(-1750 2350);
DISPLAY 1.234043 (-1750 2350);
PAINT GREEN (-1750 2350);
DISPLAY INVISIBLE (-1750 2350);
FORCEPROP 1 LAST HDL_TAP TRUE
J 2
(-2075 2275);
DISPLAY 1.234043 (-2075 2275);
PAINT GREEN (-2075 2275);
DISPLAY INVISIBLE (-2075 2275);
FORCEPROP 1 LAST PATH I93
J 2
(-1750 2400);
DISPLAY 0.936170 (-1750 2400);
PAINT GREEN (-1750 2400);
DISPLAY INVISIBLE (-1750 2400);
FORCEADD TAP..6
R 2
(-1750 2550);
FORCEPROP 3 LASTPIN (-1800 2550) SIG_NAME M_M_DQ<17>
J 0
(-1790 2560);
DISPLAY 0.659574 (-1790 2560);
PAINT MONO (-1790 2560);
DISPLAY INVISIBLE (-1790 2560);
FORCEPROP 1 LASTPIN (-1800 2550) BN 17
J 2
(-1750 2560);
DISPLAY 0.617021 (-1750 2560);
PAINT PINK (-1750 2560);
FORCEPROP 2 LAST CDS_LIB mstr_standard
J 2
(-1750 2550);
DISPLAY 0.787234 (-1750 2550);
PAINT MONO (-1750 2550);
DISPLAY INVISIBLE (-1750 2550);
FORCEPROP 1 LAST BODY_TYPE PLUMBING
J 2
(-1750 2500);
DISPLAY 1.234043 (-1750 2500);
PAINT GREEN (-1750 2500);
DISPLAY INVISIBLE (-1750 2500);
FORCEPROP 1 LAST HDL_TAP TRUE
J 2
(-2075 2425);
DISPLAY 1.234043 (-2075 2425);
PAINT GREEN (-2075 2425);
DISPLAY INVISIBLE (-2075 2425);
FORCEPROP 1 LAST PATH I94
J 2
(-1750 2550);
DISPLAY 0.936170 (-1750 2550);
PAINT GREEN (-1750 2550);
DISPLAY INVISIBLE (-1750 2550);
FORCEADD TAP..6
R 2
(-1750 2600);
FORCEPROP 3 LASTPIN (-1800 2600) SIG_NAME M_M_DQ<16>
J 0
(-1790 2610);
DISPLAY 0.659574 (-1790 2610);
PAINT MONO (-1790 2610);
DISPLAY INVISIBLE (-1790 2610);
FORCEPROP 1 LASTPIN (-1800 2600) BN 16
J 2
(-1750 2610);
DISPLAY 0.617021 (-1750 2610);
PAINT PINK (-1750 2610);
FORCEPROP 2 LAST CDS_LIB mstr_standard
J 2
(-1750 2600);
DISPLAY 0.787234 (-1750 2600);
PAINT MONO (-1750 2600);
DISPLAY INVISIBLE (-1750 2600);
FORCEPROP 1 LAST BODY_TYPE PLUMBING
J 2
(-1750 2550);
DISPLAY 1.234043 (-1750 2550);
PAINT GREEN (-1750 2550);
DISPLAY INVISIBLE (-1750 2550);
FORCEPROP 1 LAST HDL_TAP TRUE
J 2
(-2075 2475);
DISPLAY 1.234043 (-2075 2475);
PAINT GREEN (-2075 2475);
DISPLAY INVISIBLE (-2075 2475);
FORCEPROP 1 LAST PATH I95
J 2
(-1750 2600);
DISPLAY 0.936170 (-1750 2600);
PAINT GREEN (-1750 2600);
DISPLAY INVISIBLE (-1750 2600);
FORCEADD TAP..6
R 2
(-1750 2450);
FORCEPROP 3 LASTPIN (-1800 2450) SIG_NAME M_M_DQ<15>
J 0
(-1790 2460);
DISPLAY 0.659574 (-1790 2460);
PAINT MONO (-1790 2460);
DISPLAY INVISIBLE (-1790 2460);
FORCEPROP 1 LASTPIN (-1800 2450) BN 15
J 2
(-1750 2460);
DISPLAY 0.617021 (-1750 2460);
PAINT PINK (-1750 2460);
FORCEPROP 2 LAST CDS_LIB mstr_standard
J 2
(-1750 2450);
DISPLAY 0.787234 (-1750 2450);
PAINT MONO (-1750 2450);
DISPLAY INVISIBLE (-1750 2450);
FORCEPROP 1 LAST BODY_TYPE PLUMBING
J 2
(-1750 2400);
DISPLAY 1.234043 (-1750 2400);
PAINT GREEN (-1750 2400);
DISPLAY INVISIBLE (-1750 2400);
FORCEPROP 1 LAST HDL_TAP TRUE
J 2
(-2075 2325);
DISPLAY 1.234043 (-2075 2325);
PAINT GREEN (-2075 2325);
DISPLAY INVISIBLE (-2075 2325);
FORCEPROP 1 LAST PATH I96
J 2
(-1750 2450);
DISPLAY 0.936170 (-1750 2450);
PAINT GREEN (-1750 2450);
DISPLAY INVISIBLE (-1750 2450);
FORCEADD TAP..6
R 2
(-1750 2500);
FORCEPROP 3 LASTPIN (-1800 2500) SIG_NAME M_M_DQ<14>
J 0
(-1790 2510);
DISPLAY 0.659574 (-1790 2510);
PAINT MONO (-1790 2510);
DISPLAY INVISIBLE (-1790 2510);
FORCEPROP 1 LASTPIN (-1800 2500) BN 14
J 2
(-1750 2510);
DISPLAY 0.617021 (-1750 2510);
PAINT PINK (-1750 2510);
FORCEPROP 2 LAST CDS_LIB mstr_standard
J 2
(-1750 2500);
DISPLAY 0.787234 (-1750 2500);
PAINT MONO (-1750 2500);
DISPLAY INVISIBLE (-1750 2500);
FORCEPROP 1 LAST BODY_TYPE PLUMBING
J 2
(-1750 2450);
DISPLAY 1.234043 (-1750 2450);
PAINT GREEN (-1750 2450);
DISPLAY INVISIBLE (-1750 2450);
FORCEPROP 1 LAST HDL_TAP TRUE
J 2
(-2075 2375);
DISPLAY 1.234043 (-2075 2375);
PAINT GREEN (-2075 2375);
DISPLAY INVISIBLE (-2075 2375);
FORCEPROP 1 LAST PATH I97
J 2
(-1750 2500);
DISPLAY 0.936170 (-1750 2500);
PAINT GREEN (-1750 2500);
DISPLAY INVISIBLE (-1750 2500);
FORCEADD TAP..6
R 2
(-1750 2150);
FORCEPROP 3 LASTPIN (-1800 2150) SIG_NAME M_M_DQ<9>
J 0
(-1790 2160);
DISPLAY 0.659574 (-1790 2160);
PAINT MONO (-1790 2160);
DISPLAY INVISIBLE (-1790 2160);
FORCEPROP 1 LASTPIN (-1800 2150) BN 9
J 2
(-1750 2160);
DISPLAY 0.617021 (-1750 2160);
PAINT PINK (-1750 2160);
FORCEPROP 2 LAST CDS_LIB mstr_standard
J 2
(-1750 2150);
DISPLAY 0.787234 (-1750 2150);
PAINT MONO (-1750 2150);
DISPLAY INVISIBLE (-1750 2150);
FORCEPROP 1 LAST BODY_TYPE PLUMBING
J 2
(-1750 2100);
DISPLAY 1.234043 (-1750 2100);
PAINT GREEN (-1750 2100);
DISPLAY INVISIBLE (-1750 2100);
FORCEPROP 1 LAST HDL_TAP TRUE
J 2
(-2075 2025);
DISPLAY 1.234043 (-2075 2025);
PAINT GREEN (-2075 2025);
DISPLAY INVISIBLE (-2075 2025);
FORCEPROP 1 LAST PATH I98
J 2
(-1750 2150);
DISPLAY 0.936170 (-1750 2150);
PAINT GREEN (-1750 2150);
DISPLAY INVISIBLE (-1750 2150);
FORCEADD TAP..6
R 2
(-1750 2250);
FORCEPROP 3 LASTPIN (-1800 2250) SIG_NAME M_M_DQ<11>
J 0
(-1790 2260);
DISPLAY 0.659574 (-1790 2260);
PAINT MONO (-1790 2260);
DISPLAY INVISIBLE (-1790 2260);
FORCEPROP 1 LASTPIN (-1800 2250) BN 11
J 2
(-1750 2260);
DISPLAY 0.617021 (-1750 2260);
PAINT PINK (-1750 2260);
FORCEPROP 2 LAST CDS_LIB mstr_standard
J 2
(-1750 2250);
DISPLAY 0.787234 (-1750 2250);
PAINT MONO (-1750 2250);
DISPLAY INVISIBLE (-1750 2250);
FORCEPROP 1 LAST BODY_TYPE PLUMBING
J 2
(-1750 2200);
DISPLAY 1.234043 (-1750 2200);
PAINT GREEN (-1750 2200);
DISPLAY INVISIBLE (-1750 2200);
FORCEPROP 1 LAST HDL_TAP TRUE
J 2
(-2075 2125);
DISPLAY 1.234043 (-2075 2125);
PAINT GREEN (-2075 2125);
DISPLAY INVISIBLE (-2075 2125);
FORCEPROP 1 LAST PATH I99
J 2
(-1750 2250);
DISPLAY 0.936170 (-1750 2250);
PAINT GREEN (-1750 2250);
DISPLAY INVISIBLE (-1750 2250);
FORCEADD INTEL_CORP_BPAGE..1
(2650 500);
FORCEPROP 1 LAST CDS_CON_LAST_MODIFIED Fri Jun 16 17:48:32 2017
J 0
(1225 825);
DISPLAY 0.787234 (1225 825);
PAINT ORANGE (1225 825);
DISPLAY INVISIBLE (1225 825);
FORCEPROP 1 LAST CUSTOM_TXT_CDS <CURRENT_DESIGN_SHEET> OF <TOTAL_DESIGN_SHEETS>
J 0
(2150 525);
PAINT ORANGE (2150 525);
FORCEPROP 1 LAST CUSTOM_TXT_CDS <CON_LAST_MODIFIED>
J 0
(-1350 600);
PAINT ORANGE (-1350 600);
FORCEPROP 2 LAST CUSTOM_TXT_CDS <XR_PAGE_TITLE>
J 0
(-5240 5750);
DISPLAY 0.638298 (-5240 5750);
PAINT PINK (-5240 5750);
DISPLAY INVISIBLE (-5240 5750);
FORCEPROP 1 LAST SCH_TITLE CPU1 DDR4 CH M DIMM0
J 0
(-5300 550);
DISPLAY 1.212766 (-5300 550);
PAINT WHITE (-5300 550);
FORCEPROP 2 LAST CDS_LIB mstr_symbols
J 0
(2650 500);
DISPLAY 0.787234 (2650 500);
PAINT MONO (2650 500);
DISPLAY INVISIBLE (2650 500);
FORCEPROP 2 LAST PAGE_BORDER TRUE
J 0
(-5240 5750);
DISPLAY 0.680851 (-5240 5750);
PAINT PINK (-5240 5750);
DISPLAY INVISIBLE (-5240 5750);
FORCEPROP 1 LAST COMMENT_BODY TRUE
J 0
(2660 510);
DISPLAY 0.382979 (2660 510);
PAINT GREEN (2660 510);
DISPLAY INVISIBLE (2660 510);
FORCEPROP 2 LAST CDS_XR_PAGE_TITLE CR-87 : @BASEBOARD_FAB2_LIB.BASEBOARD_FAB2(SCH_1):PAGE87
J 0
(-5240 5750);
DISPLAY 0.638298 (-5240 5750);
PAINT PINK (-5240 5750);
DISPLAY INVISIBLE (-5240 5750);
FORCEADD BOM_NOTE..1
(-4975 5250);
FORCEPROP 0 LAST L1 STUFF FOR SKU A & B
J 0
(-5125 5150);
DISPLAY 1.063830 (-5125 5150);
PAINT WHITE (-5125 5150);
FORCEPROP 2 LAST BOM_COST SB
J 0
(-5125 5225);
DISPLAY 1.361702 (-5125 5225);
PAINT ORANGE (-5125 5225);
DISPLAY INVISIBLE (-5125 5225);
FORCEPROP 2 LAST CDS_LIB mstr_symbols
J 0
(-4975 5250);
PAINT ORANGE (-4975 5250);
DISPLAY INVISIBLE (-4975 5250);
FORCEPROP 1 LAST COMMENT_BODY TRUE
J 0
(-4950 5350);
DISPLAY 1.319149 (-4950 5350);
PAINT ORANGE (-4950 5350);
DISPLAY INVISIBLE (-4950 5350);
FORCEPROP 2 LAST ROOM SB_HEADERS
J 0
(-5125 5225);
DISPLAY 1.361702 (-5125 5225);
PAINT ORANGE (-5125 5225);
DISPLAY INVISIBLE (-5125 5225);
WIRE 16 -1 (-1450 2550)(-1450 2450);
WIRE 16 -1 (-1450 2450)(-1100 2450);
WIRE 16 -1 (-1100 2400)(-1100 2450);
WIRE 16 -1 (-1100 2450)(-900 2450);
WIRE 16 -1 (-1100 2350)(-1100 2400);
WIRE 16 -1 (-1100 2400)(-900 2400);
WIRE 16 -1 (-1100 2300)(-1100 2350);
WIRE 16 -1 (-1100 2350)(-900 2350);
WIRE 16 -1 (-1100 2250)(-1100 2300);
WIRE 16 -1 (-1100 2300)(-900 2300);
WIRE 16 -1 (-1100 2200)(-1100 2250);
WIRE 16 -1 (-1100 2250)(-900 2250);
WIRE 16 -1 (-1100 2150)(-1100 2200);
WIRE 16 -1 (-1100 2200)(-900 2200);
WIRE 16 -1 (-1100 2100)(-1100 2150);
WIRE 16 -1 (-1100 2150)(-900 2150);
WIRE 16 -1 (-1100 2050)(-1100 2100);
WIRE 16 -1 (-1100 2100)(-900 2100);
WIRE 16 -1 (-1100 2000)(-1100 2050);
WIRE 16 -1 (-1100 2050)(-900 2050);
WIRE 16 -1 (-1100 1950)(-1100 2000);
WIRE 16 -1 (-1100 2000)(-900 2000);
WIRE 16 -1 (-1100 1900)(-1100 1950);
WIRE 16 -1 (-1100 1950)(-900 1950);
WIRE 16 -1 (-1100 1850)(-1100 1900);
WIRE 16 -1 (-1100 1900)(-900 1900);
WIRE 16 -1 (-1100 1800)(-1100 1850);
WIRE 16 -1 (-1100 1850)(-900 1850);
WIRE 16 -1 (-1100 1750)(-1100 1800);
WIRE 16 -1 (-1100 1800)(-900 1800);
WIRE 16 -1 (-1100 1700)(-1100 1750);
WIRE 16 -1 (-1100 1750)(-900 1750);
WIRE 16 -1 (-1100 1650)(-1100 1700);
WIRE 16 -1 (-1100 1700)(-900 1700);
WIRE 16 -1 (-1100 1600)(-1100 1650);
WIRE 16 -1 (-1100 1650)(-900 1650);
WIRE 16 -1 (-1100 1550)(-1100 1600);
WIRE 16 -1 (-1100 1600)(-900 1600);
WIRE 16 -1 (-1100 1500)(-1100 1550);
WIRE 16 -1 (-1100 1550)(-900 1550);
WIRE 16 -1 (-1100 1450)(-1100 1500);
WIRE 16 -1 (-1100 1500)(-900 1500);
WIRE 16 -1 (-1100 1400)(-1100 1450);
WIRE 16 -1 (-1100 1450)(-900 1450);
WIRE 16 -1 (-1100 1350)(-1100 1400);
WIRE 16 -1 (-1100 1400)(-900 1400);
WIRE 16 -1 (-1100 1300)(-1100 1350);
WIRE 16 -1 (-1100 1350)(-900 1350);
WIRE 16 -1 (-1100 1250)(-1100 1300);
WIRE 16 -1 (-1100 1300)(-900 1300);
WIRE 16 -1 (-1100 1200)(-1100 1250);
WIRE 16 -1 (-1100 1250)(-900 1250);
WIRE 16 -1 (-1100 1200)(-900 1200);
WIRE 16 -1 (2500 1200)(2500 1300);
WIRE 16 -1 (2500 1300)(2500 1350);
WIRE 16 -1 (2500 1300)(2300 1300);
WIRE 16 -1 (2500 1350)(2500 1400);
WIRE 16 -1 (2500 1350)(2300 1350);
WIRE 16 -1 (2500 1400)(2500 1450);
WIRE 16 -1 (2500 1400)(2300 1400);
WIRE 16 -1 (2500 1450)(2500 1500);
WIRE 16 -1 (2500 1450)(2300 1450);
WIRE 16 -1 (2500 1500)(2500 1550);
WIRE 16 -1 (2500 1500)(2300 1500);
WIRE 16 -1 (2500 1550)(2500 1600);
WIRE 16 -1 (2500 1550)(2300 1550);
WIRE 16 -1 (2500 1600)(2500 1650);
WIRE 16 -1 (2500 1600)(2300 1600);
WIRE 16 -1 (2500 1650)(2500 1700);
WIRE 16 -1 (2500 1650)(2300 1650);
WIRE 16 -1 (2500 1700)(2500 1750);
WIRE 16 -1 (2500 1700)(2300 1700);
WIRE 16 -1 (2500 1750)(2500 1800);
WIRE 16 -1 (2500 1750)(2300 1750);
WIRE 16 -1 (2500 1800)(2500 1850);
WIRE 16 -1 (2500 1800)(2300 1800);
WIRE 16 -1 (2500 1850)(2500 1900);
WIRE 16 -1 (2500 1850)(2300 1850);
WIRE 16 -1 (2500 1900)(2500 1950);
WIRE 16 -1 (2500 1900)(2300 1900);
WIRE 16 -1 (2500 1950)(2500 2000);
WIRE 16 -1 (2500 1950)(2300 1950);
WIRE 16 -1 (2500 2000)(2500 2050);
WIRE 16 -1 (2500 2000)(2300 2000);
WIRE 16 -1 (2500 2050)(2500 2100);
WIRE 16 -1 (2500 2050)(2300 2050);
WIRE 16 -1 (2500 2100)(2500 2150);
WIRE 16 -1 (2500 2100)(2300 2100);
WIRE 16 -1 (2500 2150)(2500 2200);
WIRE 16 -1 (2500 2150)(2300 2150);
WIRE 16 -1 (2500 2200)(2500 2250);
WIRE 16 -1 (2500 2200)(2300 2200);
WIRE 16 -1 (2500 2250)(2500 2300);
WIRE 16 -1 (2500 2250)(2300 2250);
WIRE 16 -1 (2500 2300)(2500 2350);
WIRE 16 -1 (2500 2300)(2300 2300);
WIRE 16 -1 (2500 2350)(2500 2400);
WIRE 16 -1 (2500 2350)(2300 2350);
WIRE 16 -1 (2500 2400)(2500 2450);
WIRE 16 -1 (2500 2400)(2300 2400);
WIRE 16 -1 (2500 2450)(2500 2500);
WIRE 16 -1 (2500 2450)(2300 2450);
WIRE 16 -1 (2500 2500)(2500 2550);
WIRE 16 -1 (2500 2500)(2300 2500);
WIRE 16 -1 (2500 2550)(2500 2600);
WIRE 16 -1 (2500 2550)(2300 2550);
WIRE 16 -1 (2500 2600)(2500 2650);
WIRE 16 -1 (2500 2600)(2300 2600);
WIRE 16 -1 (2500 2650)(2500 2700);
WIRE 16 -1 (2500 2650)(2300 2650);
WIRE 16 -1 (2500 2700)(2500 2750);
WIRE 16 -1 (2500 2700)(2300 2700);
WIRE 16 -1 (2500 2750)(2500 2800);
WIRE 16 -1 (2500 2750)(2300 2750);
WIRE 16 -1 (2500 2800)(2500 2850);
WIRE 16 -1 (2500 2800)(2300 2800);
WIRE 16 -1 (2500 2850)(2500 2900);
WIRE 16 -1 (2500 2850)(2300 2850);
WIRE 16 -1 (2500 2900)(2500 2950);
WIRE 16 -1 (2500 2900)(2300 2900);
WIRE 16 -1 (2500 2950)(2500 3000);
WIRE 16 -1 (2500 2950)(2300 2950);
WIRE 16 -1 (2500 3000)(2500 3050);
WIRE 16 -1 (2500 3000)(2300 3000);
WIRE 16 -1 (2500 3050)(2500 3100);
WIRE 16 -1 (2500 3050)(2300 3050);
WIRE 16 -1 (2500 3100)(2500 3150);
WIRE 16 -1 (2500 3100)(2300 3100);
WIRE 16 -1 (2500 3150)(2500 3200);
WIRE 16 -1 (2500 3150)(2300 3150);
WIRE 16 -1 (2500 3200)(2500 3250);
WIRE 16 -1 (2500 3200)(2300 3200);
WIRE 16 -1 (2500 3250)(2500 3300);
WIRE 16 -1 (2500 3250)(2300 3250);
WIRE 16 -1 (2500 3300)(2500 3350);
WIRE 16 -1 (2500 3300)(2300 3300);
WIRE 16 -1 (2500 3350)(2500 3400);
WIRE 16 -1 (2500 3350)(2300 3350);
WIRE 16 -1 (2500 3400)(2500 3450);
WIRE 16 -1 (2500 3400)(2300 3400);
WIRE 16 -1 (2500 3450)(2500 3500);
WIRE 16 -1 (2500 3450)(2300 3450);
WIRE 16 -1 (2500 3500)(2500 3550);
WIRE 16 -1 (2500 3500)(2300 3500);
WIRE 16 -1 (2500 3550)(2500 3600);
WIRE 16 -1 (2500 3550)(2300 3550);
WIRE 16 -1 (2500 3600)(2300 3600);
WIRE 16 -1 (-5000 2000)(-5000 1900);
WIRE 16 -1 (-5000 2000)(-3200 2000);
WIRE 16 -1 (-3200 1950)(-3200 2000);
WIRE 16 -1 (-3200 2000)(-3000 2000);
WIRE 16 -1 (-3000 1950)(-3200 1950);
WIRE 16 -1 (-4650 1450)(-4650 1350);
WIRE 16 -1 (-1100 3000)(-1100 2900);
WIRE 16 -1 (-1100 2900)(-1100 2850);
WIRE 16 -1 (-1100 2900)(-900 2900);
WIRE 16 -1 (-1100 2800)(-1100 2850);
WIRE 16 -1 (-1100 2850)(-900 2850);
WIRE 16 -1 (-1100 2800)(-1100 2750);
WIRE 16 -1 (-1100 2800)(-900 2800);
WIRE 16 -1 (-1100 2750)(-1100 2700);
WIRE 16 -1 (-1100 2750)(-900 2750);
WIRE 16 -1 (-1100 2700)(-900 2700);
WIRE 16 -1 (-5000 2100)(-5000 2200);
WIRE 16 -1 (-3200 2100)(-5000 2100);
WIRE 16 -1 (-3200 2050)(-3200 2100);
WIRE 16 -1 (-3000 2100)(-3200 2100);
WIRE 16 -1 (-3000 2050)(-3200 2050);
WIRE 16 -1 (300 2900)(300 2975);
WIRE 16 -1 (300 2850)(300 2900);
WIRE 16 -1 (100 2900)(300 2900);
WIRE 16 -1 (100 2850)(300 2850);
WIRE 16 -1 (1100 1200)(1100 1300);
WIRE 16 -1 (1100 1300)(1100 1350);
WIRE 16 -1 (1100 1300)(1300 1300);
WIRE 16 -1 (1100 1350)(1100 1400);
WIRE 16 -1 (1100 1350)(1300 1350);
WIRE 16 -1 (1100 1400)(1100 1450);
WIRE 16 -1 (1100 1400)(1300 1400);
WIRE 16 -1 (1100 1450)(1100 1500);
WIRE 16 -1 (1100 1450)(1300 1450);
WIRE 16 -1 (1100 1500)(1100 1550);
WIRE 16 -1 (1100 1500)(1300 1500);
WIRE 16 -1 (1100 1550)(1100 1600);
WIRE 16 -1 (1100 1550)(1300 1550);
WIRE 16 -1 (1100 1600)(1100 1650);
WIRE 16 -1 (1100 1600)(1300 1600);
WIRE 16 -1 (1100 1650)(1100 1700);
WIRE 16 -1 (1100 1650)(1300 1650);
WIRE 16 -1 (1100 1700)(1100 1750);
WIRE 16 -1 (1100 1700)(1300 1700);
WIRE 16 -1 (1100 1750)(1100 1800);
WIRE 16 -1 (1100 1750)(1300 1750);
WIRE 16 -1 (1100 1800)(1100 1850);
WIRE 16 -1 (1100 1800)(1300 1800);
WIRE 16 -1 (1100 1850)(1100 1900);
WIRE 16 -1 (1100 1850)(1300 1850);
WIRE 16 -1 (1100 1900)(1100 1950);
WIRE 16 -1 (1100 1900)(1300 1900);
WIRE 16 -1 (1100 1950)(1100 2000);
WIRE 16 -1 (1100 1950)(1300 1950);
WIRE 16 -1 (1100 2000)(1100 2050);
WIRE 16 -1 (1100 2000)(1300 2000);
WIRE 16 -1 (1100 2050)(1100 2100);
WIRE 16 -1 (1100 2050)(1300 2050);
WIRE 16 -1 (1100 2100)(1100 2150);
WIRE 16 -1 (1100 2100)(1300 2100);
WIRE 16 -1 (1100 2150)(1100 2200);
WIRE 16 -1 (1100 2150)(1300 2150);
WIRE 16 -1 (1100 2200)(1100 2250);
WIRE 16 -1 (1100 2200)(1300 2200);
WIRE 16 -1 (1100 2250)(1100 2300);
WIRE 16 -1 (1100 2250)(1300 2250);
WIRE 16 -1 (1100 2300)(1100 2350);
WIRE 16 -1 (1100 2300)(1300 2300);
WIRE 16 -1 (1100 2350)(1100 2400);
WIRE 16 -1 (1100 2350)(1300 2350);
WIRE 16 -1 (1100 2400)(1100 2450);
WIRE 16 -1 (1100 2400)(1300 2400);
WIRE 16 -1 (1100 2450)(1100 2500);
WIRE 16 -1 (1100 2450)(1300 2450);
WIRE 16 -1 (1100 2500)(1100 2550);
WIRE 16 -1 (1100 2500)(1300 2500);
WIRE 16 -1 (1100 2550)(1100 2600);
WIRE 16 -1 (1100 2550)(1300 2550);
WIRE 16 -1 (1100 2600)(1100 2650);
WIRE 16 -1 (1100 2600)(1300 2600);
WIRE 16 -1 (1100 2650)(1100 2700);
WIRE 16 -1 (1100 2650)(1300 2650);
WIRE 16 -1 (1100 2700)(1100 2750);
WIRE 16 -1 (1100 2700)(1300 2700);
WIRE 16 -1 (1100 2750)(1100 2800);
WIRE 16 -1 (1100 2750)(1300 2750);
WIRE 16 -1 (1100 2800)(1100 2850);
WIRE 16 -1 (1100 2800)(1300 2800);
WIRE 16 -1 (1100 2850)(1100 2900);
WIRE 16 -1 (1100 2850)(1300 2850);
WIRE 16 -1 (1100 2900)(1100 2950);
WIRE 16 -1 (1100 2900)(1300 2900);
WIRE 16 -1 (1100 2950)(1100 3000);
WIRE 16 -1 (1100 2950)(1300 2950);
WIRE 16 -1 (1100 3000)(1100 3050);
WIRE 16 -1 (1100 3000)(1300 3000);
WIRE 16 -1 (1100 3050)(1100 3100);
WIRE 16 -1 (1100 3050)(1300 3050);
WIRE 16 -1 (1100 3100)(1100 3150);
WIRE 16 -1 (1100 3100)(1300 3100);
WIRE 16 -1 (1100 3150)(1100 3200);
WIRE 16 -1 (1100 3150)(1300 3150);
WIRE 16 -1 (1100 3200)(1100 3250);
WIRE 16 -1 (1100 3200)(1300 3200);
WIRE 16 -1 (1100 3250)(1100 3300);
WIRE 16 -1 (1100 3250)(1300 3250);
WIRE 16 -1 (1100 3300)(1100 3350);
WIRE 16 -1 (1100 3300)(1300 3300);
WIRE 16 -1 (1100 3350)(1100 3400);
WIRE 16 -1 (1100 3350)(1300 3350);
WIRE 16 -1 (1100 3400)(1100 3450);
WIRE 16 -1 (1100 3400)(1300 3400);
WIRE 16 -1 (1100 3450)(1100 3500);
WIRE 16 -1 (1100 3450)(1300 3450);
WIRE 16 -1 (1100 3500)(1100 3550);
WIRE 16 -1 (1100 3500)(1300 3500);
WIRE 16 -1 (1100 3550)(1100 3600);
WIRE 16 -1 (1100 3550)(1300 3550);
WIRE 16 -1 (1100 3600)(1300 3600);
WIRE 16 -1 (-1250 2700)(-1250 2600);
WIRE 16 -1 (-1250 2600)(-1100 2600);
WIRE 16 -1 (-1100 2550)(-1100 2600);
WIRE 16 -1 (-1100 2600)(-900 2600);
WIRE 16 -1 (-1100 2550)(-900 2550);
WIRE 17 -1 (750 3475)(750 3575);
WIRE 17 -1 (750 3575)(750 3675);
WIRE 17 -1 (750 3675)(750 3775);
WIRE 17 -1 (750 3775)(750 3875);
WIRE 17 -1 (750 3875)(750 3975);
WIRE 17 -1 (750 3975)(750 4075);
WIRE 17 -1 (750 4075)(750 4175);
WIRE 17 -1 (750 4175)(750 4275);
WIRE 17 -1 (750 4275)(750 4375);
WIRE 17 -1 (750 4375)(750 4475);
WIRE 17 -1 (750 4475)(750 4575);
WIRE 17 -1 (750 4575)(750 4675);
WIRE 17 -1 (750 4675)(750 4775);
WIRE 17 -1 (750 4775)(750 4875);
WIRE 17 -1 (750 4875)(750 4975);
WIRE 17 -1 (1550 5200)(750 5200);
FORCEPROP 2 LAST SIG_NAME M_M_DQS_DP<17:0>
J 0
(1000 5210);
DISPLAY 0.617021 (1000 5210);
PAINT ORANGE (1000 5210);
WIRE 17 -1 (750 5175)(750 5200);
WIRE 17 -1 (750 4975)(750 5075);
WIRE 17 -1 (750 5075)(750 5175);
WIRE 17 -1 (1550 5150)(950 5150);
FORCEPROP 2 LAST SIG_NAME M_M_DQS_DN<17:0>
J 0
(1000 5160);
DISPLAY 0.617021 (1000 5160);
PAINT ORANGE (1000 5160);
WIRE 17 -1 (950 3425)(950 3525);
WIRE 17 -1 (950 3525)(950 3625);
WIRE 17 -1 (950 5125)(950 5150);
WIRE 17 -1 (950 5025)(950 5125);
WIRE 17 -1 (950 3625)(950 3725);
WIRE 17 -1 (950 3725)(950 3825);
WIRE 17 -1 (950 4925)(950 5025);
WIRE 17 -1 (950 4825)(950 4925);
WIRE 17 -1 (950 3825)(950 3925);
WIRE 17 -1 (950 3925)(950 4025);
WIRE 17 -1 (950 4725)(950 4825);
WIRE 17 -1 (950 4625)(950 4725);
WIRE 17 -1 (950 4025)(950 4125);
WIRE 17 -1 (950 4125)(950 4225);
WIRE 17 -1 (950 4525)(950 4625);
WIRE 17 -1 (950 4425)(950 4525);
WIRE 17 -1 (950 4225)(950 4325);
WIRE 17 -1 (950 4325)(950 4425);
WIRE 17 -1 (-1700 1775)(-1700 1825);
WIRE 17 -1 (-1700 1825)(-1700 1875);
WIRE 17 -1 (-1700 1875)(-1700 1925);
WIRE 17 -1 (-1700 1925)(-1700 1975);
WIRE 17 -1 (-1700 1975)(-1700 2025);
WIRE 17 -1 (-1700 2025)(-1700 2075);
WIRE 17 -1 (-1700 2075)(-1700 2125);
WIRE 17 -1 (-1700 2125)(-1700 2175);
WIRE 17 -1 (-1700 2175)(-1700 2225);
WIRE 17 -1 (-1700 2225)(-1700 2275);
WIRE 17 -1 (-1700 2275)(-1700 2325);
WIRE 17 -1 (-1700 2325)(-1700 2375);
WIRE 17 -1 (-1700 2375)(-1700 2425);
WIRE 17 -1 (-1700 2425)(-1700 2475);
WIRE 17 -1 (-1700 2475)(-1700 2525);
WIRE 17 -1 (-1700 2525)(-1700 2575);
WIRE 17 -1 (-1700 2575)(-1700 2625);
WIRE 17 -1 (-1700 2625)(-1700 2675);
WIRE 17 -1 (-1700 2675)(-1700 2725);
WIRE 17 -1 (-1700 2725)(-1700 2775);
WIRE 17 -1 (-1700 2775)(-1700 2825);
WIRE 17 -1 (-1700 2825)(-1700 2875);
WIRE 17 -1 (-1700 2875)(-1700 2925);
WIRE 17 -1 (-1700 2925)(-1700 2975);
WIRE 17 -1 (-1700 2975)(-1700 3025);
WIRE 17 -1 (-1700 3025)(-1700 3075);
WIRE 17 -1 (-1700 3075)(-1700 3125);
WIRE 17 -1 (-1700 3125)(-1700 3175);
WIRE 17 -1 (-1700 3175)(-1700 3225);
WIRE 17 -1 (-1700 3225)(-1700 3275);
WIRE 17 -1 (-1700 3275)(-1700 3325);
WIRE 17 -1 (-1700 3325)(-1700 3375);
WIRE 17 -1 (-1700 3375)(-1700 3425);
WIRE 17 -1 (-1700 3425)(-1700 3475);
WIRE 17 -1 (-1700 3475)(-1700 3525);
WIRE 17 -1 (-1700 3525)(-1700 3575);
WIRE 17 -1 (-1700 3575)(-1700 3625);
WIRE 17 -1 (-1700 3625)(-1700 3675);
WIRE 17 -1 (-1700 3675)(-1700 3725);
WIRE 17 -1 (-1700 3725)(-1700 3775);
WIRE 17 -1 (-1700 3775)(-1700 3825);
WIRE 17 -1 (-1700 3825)(-1700 3875);
WIRE 17 -1 (-1700 3875)(-1700 3925);
WIRE 17 -1 (-1700 3925)(-1700 3975);
WIRE 17 -1 (-1700 3975)(-1700 4025);
WIRE 17 -1 (-1700 4025)(-1700 4075);
WIRE 17 -1 (-1700 4075)(-1700 4125);
WIRE 17 -1 (-1700 4125)(-1700 4175);
WIRE 17 -1 (-1700 4175)(-1700 4225);
WIRE 17 -1 (-1700 4225)(-1700 4275);
WIRE 17 -1 (-1700 4275)(-1700 4325);
WIRE 17 -1 (-1700 4325)(-1700 4375);
WIRE 17 -1 (-1700 4375)(-1700 4425);
WIRE 17 -1 (-1700 4425)(-1700 4475);
WIRE 17 -1 (-1700 4475)(-1700 4525);
WIRE 17 -1 (-1700 4525)(-1700 4575);
WIRE 17 -1 (-1700 4575)(-1700 4625);
WIRE 17 -1 (-1700 4625)(-1700 4675);
WIRE 17 -1 (-1700 4675)(-1700 4725);
WIRE 17 -1 (-1700 4725)(-1700 4775);
WIRE 17 -1 (-1700 4775)(-1700 4825);
WIRE 17 -1 (-1250 4950)(-1700 4950);
FORCEPROP 2 LAST SIG_NAME M_M_DQ<63:0>
J 0
(-1660 4960);
DISPLAY 0.617021 (-1660 4960);
PAINT ORANGE (-1660 4960);
WIRE 17 -1 (-1700 4950)(-1700 4925);
WIRE 17 -1 (-1700 4825)(-1700 4875);
WIRE 17 -1 (-1700 4875)(-1700 4925);
WIRE 17 -1 (-3800 4950)(-3300 4950);
FORCEPROP 2 LAST SIG_NAME M_M_MA<17:0>
J 0
(-3750 4960);
DISPLAY 0.617021 (-3750 4960);
PAINT ORANGE (-3750 4960);
WIRE 17 -1 (-3300 4925)(-3300 4950);
WIRE 17 -1 (-3300 4875)(-3300 4925);
WIRE 17 -1 (-3300 4825)(-3300 4875);
WIRE 17 -1 (-3300 4775)(-3300 4825);
WIRE 17 -1 (-3300 4725)(-3300 4775);
WIRE 17 -1 (-3300 4675)(-3300 4725);
WIRE 17 -1 (-3300 4625)(-3300 4675);
WIRE 17 -1 (-3300 4575)(-3300 4625);
WIRE 17 -1 (-3300 4525)(-3300 4575);
WIRE 17 -1 (-3300 4475)(-3300 4525);
WIRE 17 -1 (-3300 4425)(-3300 4475);
WIRE 17 -1 (-3300 4375)(-3300 4425);
WIRE 17 -1 (-3300 4325)(-3300 4375);
WIRE 17 -1 (-3300 4275)(-3300 4325);
WIRE 17 -1 (-3300 4225)(-3300 4275);
WIRE 17 -1 (-3300 4175)(-3300 4225);
WIRE 17 -1 (-3300 4075)(-3300 4125);
WIRE 17 -1 (-3300 4125)(-3300 4175);
WIRE 17 -1 (-3300 3275)(-3300 3325);
WIRE 17 -1 (-3300 3450)(-3800 3450);
FORCEPROP 2 LAST SIG_NAME M_M_CS_N<7:0>
J 0
(-3775 3460);
DISPLAY 0.617021 (-3775 3460);
PAINT ORANGE (-3775 3460);
WIRE 17 -1 (-3300 3425)(-3300 3450);
WIRE 17 -1 (-3300 3325)(-3300 3375);
WIRE 17 -1 (-3300 3375)(-3300 3425);
WIRE 17 -1 (-3500 3725)(-3800 3725);
FORCEPROP 2 LAST SIG_NAME M_M_CLK_DN<3:0>
J 0
(-3800 3735);
DISPLAY 0.617021 (-3800 3735);
PAINT ORANGE (-3800 3735);
WIRE 17 -1 (-3500 3675)(-3500 3575);
WIRE 17 -1 (-3500 3675)(-3500 3725);
WIRE 17 -1 (-3300 3775)(-3800 3775);
FORCEPROP 2 LAST SIG_NAME M_M_CLK_DP<3:0>
J 0
(-3800 3785);
DISPLAY 0.617021 (-3800 3785);
PAINT ORANGE (-3800 3785);
WIRE 17 -1 (-3300 3725)(-3300 3775);
WIRE 17 -1 (-3300 3625)(-3300 3725);
WIRE 17 -1 (-3300 4000)(-3800 4000);
FORCEPROP 2 LAST SIG_NAME M_M_BA<1:0>
J 0
(-3775 4010);
DISPLAY 0.617021 (-3775 4010);
PAINT ORANGE (-3775 4010);
WIRE 17 -1 (-3300 4000)(-3300 3975);
WIRE 17 -1 (-3300 3925)(-3300 3975);
WIRE 17 -1 (-3300 2525)(-3300 2575);
WIRE 17 -1 (-3300 2575)(-3300 2625);
WIRE 17 -1 (-3300 2900)(-3800 2900);
FORCEPROP 2 LAST SIG_NAME M_M_ECC<7:0>
J 0
(-3775 2910);
DISPLAY 0.617021 (-3775 2910);
PAINT ORANGE (-3775 2910);
WIRE 17 -1 (-3300 2625)(-3300 2675);
WIRE 17 -1 (-3300 2675)(-3300 2725);
WIRE 17 -1 (-3300 2875)(-3300 2900);
WIRE 17 -1 (-3300 2825)(-3300 2875);
WIRE 17 -1 (-3300 2725)(-3300 2775);
WIRE 17 -1 (-3300 2775)(-3300 2825);
WIRE 17 -1 (-3300 3225)(-3800 3225);
FORCEPROP 2 LAST SIG_NAME M_M_CKE<3:0>
J 0
(-3775 3235);
DISPLAY 0.617021 (-3775 3235);
PAINT ORANGE (-3775 3235);
WIRE 17 -1 (-3300 3125)(-3300 3175);
WIRE 17 -1 (-3300 3175)(-3300 3225);
WIRE 17 -1 (-3300 3900)(-3800 3900);
FORCEPROP 2 LAST SIG_NAME M_M_BG<1:0>
J 0
(-3775 3910);
DISPLAY 0.617021 (-3775 3910);
PAINT ORANGE (-3775 3910);
WIRE 17 -1 (-3300 3875)(-3300 3900);
WIRE 17 -1 (-3300 3825)(-3300 3875);
WIRE 17 -1 (-3300 3100)(-3800 3100);
FORCEPROP 2 LAST SIG_NAME M_M_ODT<3:0>
J 0
(-3775 3110);
DISPLAY 0.617021 (-3775 3110);
PAINT ORANGE (-3775 3110);
WIRE 17 -1 (-3300 3025)(-3300 3100);
WIRE 17 -1 (-3300 2975)(-3300 3025);
WIRE 16 -1 (-3850 1650)(-3000 1650);
FORCEPROP 2 LAST SIG_NAME TP_CH_M_DIMM_M0_RFU_2
J 0
(-3800 1660);
DISPLAY 0.617021 (-3800 1660);
PAINT ORANGE (-3800 1660);
FORCEPROP 2 LASTPROP $XRERR UNIQUE?
J 0
(-4090 1650);
DISPLAY 0.638298 (-4090 1650);
PAINT MONO (-4090 1650);
DISPLAY INVISIBLE (-4090 1650);
WIRE 16 -1 (-3000 4900)(-3200 4900);
WIRE 16 -1 (-3000 4850)(-3200 4850);
WIRE 16 -1 (-3000 4800)(-3200 4800);
WIRE 16 -1 (-3000 4700)(-3200 4700);
WIRE 16 -1 (-1800 3700)(-2000 3700);
WIRE 16 -1 (-4650 1750)(-4750 1750);
WIRE 16 -1 (-4650 1750)(-4650 1650);
WIRE 16 -1 (-3000 1750)(-4650 1750);
FORCEPROP 2 LAST SIG_NAME M_M_VREF
J 0
(-3750 1760);
DISPLAY 0.617021 (-3750 1760);
PAINT ORANGE (-3750 1760);
WIRE 16 -1 (-3850 1600)(-3000 1600);
FORCEPROP 2 LAST SIG_NAME TP_CH_M_DIMM_M0_RFU_1
J 0
(-3800 1610);
DISPLAY 0.617021 (-3800 1610);
PAINT ORANGE (-3800 1610);
FORCEPROP 2 LASTPROP $XRERR UNIQUE?
J 0
(-4090 1600);
DISPLAY 0.638298 (-4090 1600);
PAINT MONO (-4090 1600);
DISPLAY INVISIBLE (-4090 1600);
WIRE 16 -1 (-3850 1550)(-3000 1550);
FORCEPROP 2 LAST SIG_NAME TP_CH_M_DIMM_M0_RFU_0
J 0
(-3800 1560);
DISPLAY 0.617021 (-3800 1560);
PAINT ORANGE (-3800 1560);
FORCEPROP 2 LASTPROP $XRERR UNIQUE?
J 0
(-4090 1550);
DISPLAY 0.638298 (-4090 1550);
PAINT MONO (-4090 1550);
DISPLAY INVISIBLE (-4090 1550);
WIRE 16 -1 (-3000 1900)(-3800 1900);
WIRE 16 -1 (-3800 1850)(-3000 1850);
FORCEPROP 2 LAST SIG_NAME SMB_DDR_KLM_VPP_SCL
J 0
(-3760 1860);
DISPLAY 0.617021 (-3760 1860);
PAINT ORANGE (-3760 1860);
WIRE 16 -1 (-3850 1450)(-3000 1450);
FORCEPROP 2 LAST SIG_NAME FM_ADR_COMPLETE_KLM_N
J 0
(-3800 1460);
DISPLAY 0.617021 (-3800 1460);
PAINT ORANGE (-3800 1460);
WIRE 16 -1 (-3400 2800)(-3800 2800);
FORCEPROP 2 LAST SIG_NAME M_KLM_RST_N
J 0
(-3775 2810);
DISPLAY 0.617021 (-3775 2810);
PAINT ORANGE (-3775 2810);
WIRE 16 -1 (-3400 2350)(-3400 2800);
WIRE 16 -1 (-3000 2350)(-3400 2350);
WIRE 16 -1 (-3350 2850)(-3800 2850);
FORCEPROP 2 LAST SIG_NAME M_M_PAR
J 0
(-3775 2860);
DISPLAY 0.617021 (-3775 2860);
PAINT ORANGE (-3775 2860);
WIRE 16 -1 (-3350 2400)(-3350 2850);
WIRE 16 -1 (-3000 2400)(-3350 2400);
WIRE 16 -1 (-4175 2600)(-3450 2600);
FORCEPROP 2 LAST SIG_NAME FM_DIMM_EVENT_COD_N
J 0
(-4151 2618);
DISPLAY 0.617021 (-4151 2618);
PAINT ORANGE (-4151 2618);
WIRE 16 -1 (-3450 2300)(-3450 2600);
WIRE 16 -1 (-3450 2300)(-3000 2300);
WIRE 16 -1 (-3150 3500)(-3800 3500);
FORCEPROP 2 LAST SIG_NAME M_M_C<2>
J 0
(-3775 3510);
DISPLAY 0.617021 (-3775 3510);
PAINT ORANGE (-3775 3510);
WIRE 16 -1 (-3150 3500)(-3150 3450);
WIRE 16 -1 (-3150 3450)(-3000 3450);
WIRE 16 -1 (-3000 3250)(-3200 3250);
WIRE 16 -1 (-3000 3100)(-3200 3100);
WIRE 16 -1 (-3000 3000)(-3200 3000);
WIRE 16 -1 (-3000 2950)(-3200 2950);
WIRE 16 -1 (-3000 2850)(-3200 2850);
WIRE 16 -1 (-3000 3900)(-3200 3900);
WIRE 16 -1 (-3000 3850)(-3200 3850);
WIRE 16 -1 (-3000 3800)(-3200 3800);
WIRE 16 -1 (-3000 3700)(-3200 3700);
WIRE 16 -1 (-3000 3150)(-3200 3150);
WIRE 16 -1 (-3000 2500)(-3200 2500);
WIRE 16 -1 (-3000 2550)(-3200 2550);
WIRE 16 -1 (-3000 2600)(-3200 2600);
WIRE 16 -1 (-3000 2650)(-3200 2650);
WIRE 16 -1 (-3000 2700)(-3200 2700);
WIRE 16 -1 (-3000 2750)(-3200 2750);
WIRE 16 -1 (-3000 2800)(-3200 2800);
WIRE 16 -1 (-3000 4050)(-3200 4050);
WIRE 16 -1 (-3000 3300)(-3200 3300);
WIRE 16 -1 (-3000 3350)(-3200 3350);
WIRE 16 -1 (-3000 3950)(-3200 3950);
WIRE 16 -1 (-3000 3550)(-3400 3550);
WIRE 16 -1 (-3000 3600)(-3200 3600);
WIRE 16 -1 (-3000 3650)(-3400 3650);
WIRE 16 -1 (-3000 3400)(-3200 3400);
WIRE 16 -1 (-3000 2250)(-4025 2250);
FORCEPROP 2 LAST SIG_NAME M_M_ALERT_N
J 0
(-3975 2260);
DISPLAY 0.617021 (-3975 2260);
PAINT ORANGE (-3975 2260);
WIRE 16 -1 (-3000 2200)(-4000 2200);
FORCEPROP 2 LAST SIG_NAME M_M_ACT_N
J 0
(-3950 2210);
DISPLAY 0.617021 (-3950 2210);
PAINT ORANGE (-3950 2210);
WIRE 16 -1 (-1800 1750)(-2000 1750);
WIRE 16 -1 (-1800 2000)(-2000 2000);
WIRE 16 -1 (-1800 1950)(-2000 1950);
WIRE 16 -1 (-1800 1900)(-2000 1900);
WIRE 16 -1 (-1800 1850)(-2000 1850);
WIRE 16 -1 (-1800 1800)(-2000 1800);
WIRE 16 -1 (-1800 2050)(-2000 2050);
WIRE 16 -1 (-1800 2100)(-2000 2100);
WIRE 16 -1 (-1800 2150)(-2000 2150);
WIRE 16 -1 (-1800 2200)(-2000 2200);
WIRE 16 -1 (-1800 2300)(-2000 2300);
WIRE 16 -1 (-1800 2250)(-2000 2250);
WIRE 16 -1 (-1800 2500)(-2000 2500);
WIRE 16 -1 (-1800 2400)(-2000 2400);
WIRE 16 -1 (-1800 2450)(-2000 2450);
WIRE 16 -1 (-1800 2550)(-2000 2550);
WIRE 16 -1 (-1800 2350)(-2000 2350);
WIRE 16 -1 (-1800 2600)(-2000 2600);
WIRE 16 -1 (-1800 2650)(-2000 2650);
WIRE 16 -1 (-1800 2700)(-2000 2700);
WIRE 16 -1 (-1800 2750)(-2000 2750);
WIRE 16 -1 (-1800 2800)(-2000 2800);
WIRE 16 -1 (-1800 3050)(-2000 3050);
WIRE 16 -1 (-1800 2850)(-2000 2850);
WIRE 16 -1 (-1800 2900)(-2000 2900);
WIRE 16 -1 (-1800 2950)(-2000 2950);
WIRE 16 -1 (-1800 3000)(-2000 3000);
WIRE 16 -1 (-1800 3100)(-2000 3100);
WIRE 16 -1 (-1800 3250)(-2000 3250);
WIRE 16 -1 (-1800 3300)(-2000 3300);
WIRE 16 -1 (-1800 3150)(-2000 3150);
WIRE 16 -1 (-1800 3200)(-2000 3200);
WIRE 16 -1 (-1800 3550)(-2000 3550);
WIRE 16 -1 (-1800 3500)(-2000 3500);
WIRE 16 -1 (-1800 3350)(-2000 3350);
WIRE 16 -1 (-1800 3400)(-2000 3400);
WIRE 16 -1 (-1800 3450)(-2000 3450);
WIRE 16 -1 (-1800 3650)(-2000 3650);
WIRE 16 -1 (-1800 3600)(-2000 3600);
WIRE 16 -1 (-1800 3750)(-2000 3750);
WIRE 16 -1 (-1800 3800)(-2000 3800);
WIRE 16 -1 (-1800 3850)(-2000 3850);
WIRE 16 -1 (-1800 3900)(-2000 3900);
WIRE 16 -1 (-1800 3950)(-2000 3950);
WIRE 16 -1 (-1800 4000)(-2000 4000);
WIRE 16 -1 (-1800 4050)(-2000 4050);
WIRE 16 -1 (-3000 4750)(-3200 4750);
WIRE 16 -1 (-3000 4600)(-3200 4600);
WIRE 16 -1 (-3000 4550)(-3200 4550);
WIRE 16 -1 (-3000 4150)(-3200 4150);
WIRE 16 -1 (-3000 4500)(-3200 4500);
WIRE 16 -1 (-3000 4450)(-3200 4450);
WIRE 16 -1 (-3000 4400)(-3200 4400);
WIRE 16 -1 (-3000 4350)(-3200 4350);
WIRE 16 -1 (-3000 4300)(-3200 4300);
WIRE 16 -1 (-3000 4250)(-3200 4250);
WIRE 16 -1 (-3000 4200)(-3200 4200);
WIRE 16 -1 (-3000 4650)(-3200 4650);
WIRE 16 -1 (-3000 4100)(-3200 4100);
WIRE 16 -1 (-1800 4100)(-2000 4100);
WIRE 16 -1 (-1800 4150)(-2000 4150);
WIRE 16 -1 (-1800 4200)(-2000 4200);
WIRE 16 -1 (-1800 4250)(-2000 4250);
WIRE 16 -1 (-1800 4300)(-2000 4300);
WIRE 16 -1 (-1800 4350)(-2000 4350);
WIRE 16 -1 (-1800 4400)(-2000 4400);
WIRE 16 -1 (-1800 4450)(-2000 4450);
WIRE 16 -1 (-1800 4600)(-2000 4600);
WIRE 16 -1 (-1800 4500)(-2000 4500);
WIRE 16 -1 (-1800 4550)(-2000 4550);
WIRE 16 -1 (-1800 4850)(-2000 4850);
WIRE 16 -1 (-1800 4800)(-2000 4800);
WIRE 16 -1 (-1800 4650)(-2000 4650);
WIRE 16 -1 (-1800 4700)(-2000 4700);
WIRE 16 -1 (-1800 4750)(-2000 4750);
WIRE 16 -1 (-1800 4900)(-2000 4900);
WIRE 16 -1 (650 4050)(450 4050);
WIRE 16 -1 (850 4000)(450 4000);
WIRE 16 -1 (650 3950)(450 3950);
WIRE 16 -1 (850 3900)(450 3900);
WIRE 16 -1 (650 3850)(450 3850);
WIRE 16 -1 (850 3800)(450 3800);
WIRE 16 -1 (650 3750)(450 3750);
WIRE 16 -1 (850 3700)(450 3700);
WIRE 16 -1 (650 3650)(450 3650);
WIRE 16 -1 (850 3600)(450 3600);
WIRE 16 -1 (650 3550)(450 3550);
WIRE 16 -1 (850 3500)(450 3500);
WIRE 16 -1 (650 3450)(450 3450);
WIRE 16 -1 (850 3400)(450 3400);
WIRE 16 -1 (650 4350)(450 4350);
WIRE 16 -1 (850 4300)(450 4300);
WIRE 16 -1 (650 4250)(450 4250);
WIRE 16 -1 (850 4200)(450 4200);
WIRE 16 -1 (650 4150)(450 4150);
WIRE 16 -1 (850 4100)(450 4100);
WIRE 16 -1 (850 5100)(450 5100);
WIRE 16 -1 (650 5050)(450 5050);
WIRE 16 -1 (850 5000)(450 5000);
WIRE 16 -1 (650 4950)(450 4950);
WIRE 16 -1 (850 4900)(450 4900);
WIRE 16 -1 (650 4850)(450 4850);
WIRE 16 -1 (850 4800)(450 4800);
WIRE 16 -1 (650 4750)(450 4750);
WIRE 16 -1 (850 4700)(450 4700);
WIRE 16 -1 (650 4650)(450 4650);
WIRE 16 -1 (850 4600)(450 4600);
WIRE 16 -1 (650 4550)(450 4550);
WIRE 16 -1 (850 4500)(450 4500);
WIRE 16 -1 (650 4450)(450 4450);
WIRE 16 -1 (850 4400)(450 4400);
WIRE 16 -1 (650 5150)(450 5150);
DOT 1 (-3200 2100);
DOT 1 (-1100 2300);
DOT 1 (-1100 2250);
DOT 1 (-1100 2600);
DOT 1 (-3200 2000);
DOT 1 (-1100 2050);
DOT 1 (2500 1550);
DOT 1 (1100 1850);
DOT 1 (1100 1300);
DOT 1 (1100 1350);
DOT 1 (1100 1400);
DOT 1 (1100 1450);
DOT 1 (1100 1550);
DOT 1 (1100 1600);
DOT 1 (1100 1650);
DOT 1 (1100 1800);
DOT 1 (1100 1900);
DOT 1 (1100 1950);
DOT 1 (1100 2000);
DOT 1 (1100 2050);
DOT 1 (1100 2100);
DOT 1 (1100 2150);
DOT 1 (1100 2200);
DOT 1 (1100 2250);
DOT 1 (1100 2300);
DOT 1 (1100 2350);
DOT 1 (1100 2400);
DOT 1 (1100 2450);
DOT 1 (1100 2500);
DOT 1 (1100 2550);
DOT 1 (1100 2600);
DOT 1 (1100 2700);
DOT 1 (1100 2750);
DOT 1 (1100 2800);
DOT 1 (1100 2850);
DOT 1 (1100 2900);
DOT 1 (1100 2950);
DOT 1 (1100 3000);
DOT 1 (1100 3050);
DOT 1 (1100 3100);
DOT 1 (1100 3150);
DOT 1 (1100 3200);
DOT 1 (1100 3250);
DOT 1 (1100 3300);
DOT 1 (1100 3350);
DOT 1 (1100 3400);
DOT 1 (1100 3450);
DOT 1 (1100 3500);
DOT 1 (1100 3550);
DOT 1 (2500 1300);
DOT 1 (2500 1350);
DOT 1 (2500 1400);
DOT 1 (2500 1500);
DOT 1 (2500 1450);
DOT 1 (2500 1600);
DOT 1 (2500 1650);
DOT 1 (2500 1750);
DOT 1 (2500 1700);
DOT 1 (2500 1800);
DOT 1 (2500 1850);
DOT 1 (2500 1900);
DOT 1 (2500 2000);
DOT 1 (2500 1950);
DOT 1 (2500 2050);
DOT 1 (2500 2100);
DOT 1 (2500 2150);
DOT 1 (2500 2200);
DOT 1 (2500 2250);
DOT 1 (2500 2300);
DOT 1 (2500 2400);
DOT 1 (2500 2350);
DOT 1 (2500 2450);
DOT 1 (2500 2500);
DOT 1 (2500 2550);
DOT 1 (2500 2600);
DOT 1 (2500 2650);
DOT 1 (2500 2700);
DOT 1 (2500 2750);
DOT 1 (2500 2800);
DOT 1 (2500 2900);
DOT 1 (2500 2850);
DOT 1 (2500 3000);
DOT 1 (2500 3050);
DOT 1 (2500 3100);
DOT 1 (2500 3200);
DOT 1 (2500 3150);
DOT 1 (2500 3300);
DOT 1 (2500 3250);
DOT 1 (2500 3350);
DOT 1 (2500 3400);
DOT 1 (2500 3450);
DOT 1 (2500 3550);
DOT 1 (2500 3500);
DOT 1 (-1100 2900);
DOT 1 (-1100 2800);
DOT 1 (-1100 2850);
DOT 1 (-1100 2350);
DOT 1 (-1100 2400);
DOT 1 (-1100 2450);
DOT 1 (-1100 2200);
DOT 1 (-1100 2150);
DOT 1 (-1100 2100);
DOT 1 (-1100 1850);
DOT 1 (-1100 1900);
DOT 1 (-1100 1800);
DOT 1 (-1100 1750);
DOT 1 (-1100 1700);
DOT 1 (-1100 1650);
DOT 1 (-1100 1600);
DOT 1 (-1100 1450);
DOT 1 (-1100 1550);
DOT 1 (-1100 1500);
DOT 1 (-1100 1350);
DOT 1 (-1100 1400);
DOT 1 (-1100 1300);
DOT 1 (-1100 1250);
DOT 1 (-1100 2750);
DOT 1 (-1100 2000);
DOT 1 (300 2900);
DOT 1 (-1100 1950);
DOT 1 (1100 1500);
DOT 1 (1100 1700);
DOT 1 (1100 1750);
DOT 1 (1100 2650);
DOT 1 (-4650 1750);
DOT 1 (2500 2950);
FORCENOTE
PVDDQ (SINGLE SIDE) CAP: 10UF X1, 22UF X50
(-2950 5250) 0;
DISPLAY LEFT (-2950 5250);
DISPLAY 1.021277 (-2950 5250);
PAINT PURPLE (-2950 5250);
FORCENOTE
PVDDQ (DOUBLE SIDE) CAP: 100UF X8, 47UF X41
(-2950 5200) 0;
DISPLAY LEFT (-2950 5200);
DISPLAY 1.021277 (-2950 5200);
PAINT PURPLE (-2950 5200);
FORCENOTE
PVTT CAP: 100UF X2, 47UF X1
(-2950 5300) 0;
DISPLAY LEFT (-2950 5300);
DISPLAY 1.021277 (-2950 5300);
PAINT PURPLE (-2950 5300);
FORCENOTE
PVPP CAP: 10UF X12
(-2950 5350) 0;
DISPLAY LEFT (-2950 5350);
DISPLAY 1.021277 (-2950 5350);
PAINT PURPLE (-2950 5350);
FORCENOTE
PLACE CAP NEAR DIMM CONNECTOR
(-5288 1202) 0;
DISPLAY LEFT (-5288 1202);
DISPLAY 1.595745 (-5288 1202);
PAINT PURPLE (-5288 1202);
FORCENOTE
SMBUS ADDR: 0XA8
(-4225 1009) 0;
DISPLAY LEFT (-4225 1009);
DISPLAY 1.957447 (-4225 1009);
PAINT PURPLE (-4225 1009);
FORCENOTE
CAP BETWEEN DIMM
(-2950 5425) 0;
DISPLAY LEFT (-2950 5425);
DISPLAY 1.276596 (-2950 5425);
PAINT PURPLE (-2950 5425);
QUIT
